FILE_TYPE = MACRO_DRAWING;
SET COLOR_WIRE YELLOW;
SET COLOR_PROP MONO;
SET COLOR_DOT WHITE;
SET COLOR_ARC YELLOW;
SET COLOR_BODY GREEN;
SET COLOR_NOTE MONO;
SET PROP_DISPLAY VALUE;
SET PAGE_NUMBER P80;
FORCEADD GND..1
R 2
(-7825 1350);
FORCEPROP 3 LASTPIN (-7825 1400) SIG_NAME GND\g
J 0
(-7815 1410);
DISPLAY 0.659574 (-7815 1410);
PAINT MONO (-7815 1410);
DISPLAY INVISIBLE (-7815 1410);
FORCEPROP 1 LAST VOLTAGE 0
J 0
(-7825 1350);
PAINT SKYBLUE (-7825 1350);
DISPLAY INVISIBLE (-7825 1350);
FORCEPROP 2 LAST CDS_LIB mstr_symbols
J 0
(-7825 1350);
DISPLAY 0.787234 (-7825 1350);
PAINT MONO (-7825 1350);
DISPLAY INVISIBLE (-7825 1350);
FORCEPROP 1 LAST SIZE 1B
J 2
(-7900 1300);
DISPLAY 1.170213 (-7900 1300);
PAINT GREEN (-7900 1300);
DISPLAY INVISIBLE (-7900 1300);
FORCEPROP 2 LAST BOM_COST MEM
J 0
(-7825 1355);
PAINT ORANGE (-7825 1355);
DISPLAY INVISIBLE (-7825 1355);
FORCEPROP 1 LAST BODY_TYPE PLUMBING
J 2
(-7780 1307);
DISPLAY 0.340426 (-7780 1307);
PAINT GREEN (-7780 1307);
DISPLAY INVISIBLE (-7780 1307);
FORCEPROP 1 LAST PATH I1
J 2
(-7900 1350);
DISPLAY 0.872340 (-7900 1350);
PAINT AQUA (-7900 1350);
DISPLAY INVISIBLE (-7900 1350);
FORCEPROP 2 LAST ROOM DDR4_GH_G
J 0
(-7825 1355);
PAINT ORANGE (-7825 1355);
DISPLAY INVISIBLE (-7825 1355);
FORCEPROP 1 LAST HDL_POWER GND
J 2
(-7825 1500);
DISPLAY 0.553191 (-7825 1500);
PAINT GREEN (-7825 1500);
DISPLAY INVISIBLE (-7825 1500);
FORCEADD OFFPAGE..1
(-6625 1650);
FORCEPROP 2 LAST $XR0 58 
J 0
(-6876 1650);
DISPLAY 0.638298 (-6876 1650);
PAINT MONO (-6876 1650);
FORCEPROP 2 LAST $XR1 79 
J 0
(-6966 1650);
DISPLAY 0.638298 (-6966 1650);
PAINT MONO (-6966 1650);
FORCEPROP 2 LAST CDS_LIB mstr_standard
J 0
(-6625 1650);
DISPLAY 0.787234 (-6625 1650);
PAINT MONO (-6625 1650);
DISPLAY INVISIBLE (-6625 1650);
FORCEPROP 1 LAST OFFPAGE TRUE
J 0
(-6300 1525);
DISPLAY 0.936170 (-6300 1525);
PAINT GREEN (-6300 1525);
DISPLAY INVISIBLE (-6300 1525);
FORCEPROP 1 LAST COMMENT_BODY TRUE
J 0
(-6500 1550);
DISPLAY 0.936170 (-6500 1550);
PAINT GREEN (-6500 1550);
DISPLAY INVISIBLE (-6500 1550);
FORCEPROP 2 LAST PATH I10
J 0
(-6875 1700);
DISPLAY 1.021277 (-6875 1700);
PAINT ORANGE (-6875 1700);
DISPLAY INVISIBLE (-6875 1700);
FORCEADD TAP..6
R 2
(-4475 3450);
FORCEPROP 3 LASTPIN (-4525 3450) SIG_NAME M_H_DQ<45>
J 0
(-4515 3460);
DISPLAY 0.659574 (-4515 3460);
PAINT MONO (-4515 3460);
DISPLAY INVISIBLE (-4515 3460);
FORCEPROP 1 LASTPIN (-4525 3450) BN 45
J 2
(-4475 3460);
DISPLAY 0.617021 (-4475 3460);
PAINT PINK (-4475 3460);
FORCEPROP 2 LAST CDS_LIB mstr_standard
J 2
(-4475 3450);
DISPLAY 0.787234 (-4475 3450);
PAINT MONO (-4475 3450);
DISPLAY INVISIBLE (-4475 3450);
FORCEPROP 1 LAST BODY_TYPE PLUMBING
J 2
(-4475 3400);
DISPLAY 1.234043 (-4475 3400);
PAINT GREEN (-4475 3400);
DISPLAY INVISIBLE (-4475 3400);
FORCEPROP 1 LAST HDL_TAP TRUE
J 2
(-4800 3325);
DISPLAY 1.234043 (-4800 3325);
PAINT GREEN (-4800 3325);
DISPLAY INVISIBLE (-4800 3325);
FORCEPROP 1 LAST PATH I100
J 2
(-4473 3450);
DISPLAY 0.872340 (-4473 3450);
PAINT GREEN (-4473 3450);
DISPLAY INVISIBLE (-4473 3450);
FORCEADD SCONN288_H44441003..2
(-2675 3750);
FORCEPROP 1 LAST LOCATION J9U1
J 0
(-3075 4850);
DISPLAY 0.617021 (-3075 4850);
PAINT AQUA (-3075 4850);
FORCEPROP 1 LAST PART_NUMBER H44441-003
J 0
(-3075 2650);
DISPLAY 0.617021 (-3075 2650);
PAINT BLUE (-3075 2650);
FORCEPROP 1 LAST MATERIAL SCONN
J 0
(-3075 4800);
DISPLAY 0.617021 (-3075 4800);
PAINT SKYBLUE (-3075 4800);
FORCEPROP 2 LASTPIN (-2225 4600) $PN 51
J 0
(-2215 4610);
DISPLAY 0.617021 (-2215 4610);
PAINT ORANGE (-2215 4610);
FORCEPROP 2 LASTPIN (-2225 4550) $PN 52
J 0
(-2215 4560);
DISPLAY 0.617021 (-2215 4560);
PAINT ORANGE (-2215 4560);
FORCEPROP 2 LASTPIN (-2225 4500) $PN 132
J 0
(-2215 4510);
DISPLAY 0.617021 (-2215 4510);
PAINT ORANGE (-2215 4510);
FORCEPROP 2 LASTPIN (-2225 4450) $PN 133
J 0
(-2215 4460);
DISPLAY 0.617021 (-2215 4460);
PAINT ORANGE (-2215 4460);
FORCEPROP 2 LASTPIN (-2225 4400) $PN 121
J 0
(-2215 4410);
DISPLAY 0.617021 (-2215 4410);
PAINT ORANGE (-2215 4410);
FORCEPROP 2 LASTPIN (-2225 4350) $PN 122
J 0
(-2215 4360);
DISPLAY 0.617021 (-2215 4360);
PAINT ORANGE (-2215 4360);
FORCEPROP 2 LASTPIN (-2225 4300) $PN 110
J 0
(-2215 4310);
DISPLAY 0.617021 (-2215 4310);
PAINT ORANGE (-2215 4310);
FORCEPROP 2 LASTPIN (-2225 4250) $PN 111
J 0
(-2215 4260);
DISPLAY 0.617021 (-2215 4260);
PAINT ORANGE (-2215 4260);
FORCEPROP 2 LASTPIN (-2225 4200) $PN 99
J 0
(-2215 4210);
DISPLAY 0.617021 (-2215 4210);
PAINT ORANGE (-2215 4210);
FORCEPROP 2 LASTPIN (-2225 4150) $PN 100
J 0
(-2215 4160);
DISPLAY 0.617021 (-2215 4160);
PAINT ORANGE (-2215 4160);
FORCEPROP 2 LASTPIN (-2225 4100) $PN 40
J 0
(-2215 4110);
DISPLAY 0.617021 (-2215 4110);
PAINT ORANGE (-2215 4110);
FORCEPROP 2 LASTPIN (-2225 4050) $PN 41
J 0
(-2215 4060);
DISPLAY 0.617021 (-2215 4060);
PAINT ORANGE (-2215 4060);
FORCEPROP 2 LASTPIN (-2225 4000) $PN 29
J 0
(-2215 4010);
DISPLAY 0.617021 (-2215 4010);
PAINT ORANGE (-2215 4010);
FORCEPROP 2 LASTPIN (-2225 3950) $PN 30
J 0
(-2215 3960);
DISPLAY 0.617021 (-2215 3960);
PAINT ORANGE (-2215 3960);
FORCEPROP 2 LASTPIN (-2225 3900) $PN 18
J 0
(-2215 3910);
DISPLAY 0.617021 (-2215 3910);
PAINT ORANGE (-2215 3910);
FORCEPROP 2 LASTPIN (-2225 3850) $PN 19
J 0
(-2215 3860);
DISPLAY 0.617021 (-2215 3860);
PAINT ORANGE (-2215 3860);
FORCEPROP 2 LASTPIN (-2225 3800) $PN 7
J 0
(-2215 3810);
DISPLAY 0.617021 (-2215 3810);
PAINT ORANGE (-2215 3810);
FORCEPROP 2 LASTPIN (-2225 3750) $PN 8
J 0
(-2215 3760);
DISPLAY 0.617021 (-2215 3760);
PAINT ORANGE (-2215 3760);
FORCEPROP 2 LASTPIN (-2225 3700) $PN 197
J 0
(-2215 3710);
DISPLAY 0.617021 (-2215 3710);
PAINT ORANGE (-2215 3710);
FORCEPROP 2 LASTPIN (-2225 3650) $PN 196
J 0
(-2215 3660);
DISPLAY 0.617021 (-2215 3660);
PAINT ORANGE (-2215 3660);
FORCEPROP 2 LASTPIN (-2225 3600) $PN 278
J 0
(-2215 3610);
DISPLAY 0.617021 (-2215 3610);
PAINT ORANGE (-2215 3610);
FORCEPROP 2 LASTPIN (-2225 3550) $PN 277
J 0
(-2215 3560);
DISPLAY 0.617021 (-2215 3560);
PAINT ORANGE (-2215 3560);
FORCEPROP 2 LASTPIN (-2225 3500) $PN 267
J 0
(-2215 3510);
DISPLAY 0.617021 (-2215 3510);
PAINT ORANGE (-2215 3510);
FORCEPROP 2 LASTPIN (-2225 3450) $PN 266
J 0
(-2215 3460);
DISPLAY 0.617021 (-2215 3460);
PAINT ORANGE (-2215 3460);
FORCEPROP 2 LASTPIN (-2225 3400) $PN 256
J 0
(-2215 3410);
DISPLAY 0.617021 (-2215 3410);
PAINT ORANGE (-2215 3410);
FORCEPROP 2 LASTPIN (-2225 3350) $PN 255
J 0
(-2215 3360);
DISPLAY 0.617021 (-2215 3360);
PAINT ORANGE (-2215 3360);
FORCEPROP 2 LASTPIN (-2225 3300) $PN 245
J 0
(-2215 3310);
DISPLAY 0.617021 (-2215 3310);
PAINT ORANGE (-2215 3310);
FORCEPROP 2 LASTPIN (-2225 3250) $PN 244
J 0
(-2215 3260);
DISPLAY 0.617021 (-2215 3260);
PAINT ORANGE (-2215 3260);
FORCEPROP 2 LASTPIN (-2225 3200) $PN 186
J 0
(-2215 3210);
DISPLAY 0.617021 (-2215 3210);
PAINT ORANGE (-2215 3210);
FORCEPROP 2 LASTPIN (-2225 3150) $PN 185
J 0
(-2215 3160);
DISPLAY 0.617021 (-2215 3160);
PAINT ORANGE (-2215 3160);
FORCEPROP 2 LASTPIN (-2225 3100) $PN 175
J 0
(-2215 3110);
DISPLAY 0.617021 (-2215 3110);
PAINT ORANGE (-2215 3110);
FORCEPROP 2 LASTPIN (-2225 3050) $PN 174
J 0
(-2215 3060);
DISPLAY 0.617021 (-2215 3060);
PAINT ORANGE (-2215 3060);
FORCEPROP 2 LASTPIN (-2225 3000) $PN 164
J 0
(-2215 3010);
DISPLAY 0.617021 (-2215 3010);
PAINT ORANGE (-2215 3010);
FORCEPROP 2 LASTPIN (-2225 2950) $PN 163
J 0
(-2215 2960);
DISPLAY 0.617021 (-2215 2960);
PAINT ORANGE (-2215 2960);
FORCEPROP 2 LASTPIN (-2225 2900) $PN 153
J 0
(-2215 2910);
DISPLAY 0.617021 (-2215 2910);
PAINT ORANGE (-2215 2910);
FORCEPROP 2 LASTPIN (-2225 2850) $PN 152
J 0
(-2215 2860);
DISPLAY 0.617021 (-2215 2860);
PAINT ORANGE (-2215 2860);
FORCEPROP 1 LAST PACK_TYPE PIP
J 0
(-3075 4900);
PAINT SKYBLUE (-3075 4900);
DISPLAY INVISIBLE (-3075 4900);
FORCEPROP 2 LAST BOM_COST MEM
J 0
(-2675 3750);
PAINT ORANGE (-2675 3750);
DISPLAY INVISIBLE (-2675 3750);
FORCEPROP 2 LAST CDS_LIB mstr_sconn
J 0
(-2675 3750);
PAINT ORANGE (-2675 3750);
DISPLAY INVISIBLE (-2675 3750);
FORCEPROP 2 LAST SEC_TYPE PIP
J 0
(-3075 4900);
DISPLAY 1.021277 (-3075 4900);
PAINT ORANGE (-3075 4900);
DISPLAY INVISIBLE (-3075 4900);
FORCEPROP 2 LAST SEC 2
J 0
(-3075 4900);
DISPLAY 0.680851 (-3075 4900);
PAINT MONO (-3075 4900);
DISPLAY INVISIBLE (-3075 4900);
FORCEPROP 2 LAST CDS_LOCATION J9U1
J 0
(-3075 4850);
DISPLAY 0.617021 (-3075 4850);
PAINT AQUA (-3075 4850);
DISPLAY INVISIBLE (-3075 4850);
FORCEPROP 1 LAST PATH I101
J 0
(-2675 4800);
PAINT GREEN (-2675 4800);
DISPLAY INVISIBLE (-2675 4800);
FORCEPROP 2 LAST ROOM DDR4_GH_H
J 0
(-2675 3750);
PAINT ORANGE (-2675 3750);
DISPLAY INVISIBLE (-2675 3750);
FORCEADD TAP..6
(-5975 3550);
FORCEPROP 3 LASTPIN (-5925 3550) SIG_NAME M_H_MA<1>
J 0
(-5915 3560);
DISPLAY 0.659574 (-5915 3560);
PAINT MONO (-5915 3560);
DISPLAY INVISIBLE (-5915 3560);
FORCEPROP 1 LASTPIN (-5925 3550) BN 1
J 0
(-5975 3560);
DISPLAY 0.617021 (-5975 3560);
PAINT PINK (-5975 3560);
FORCEPROP 2 LAST CDS_LIB mstr_standard
J 2
(-5975 3550);
DISPLAY 0.787234 (-5975 3550);
PAINT MONO (-5975 3550);
DISPLAY INVISIBLE (-5975 3550);
FORCEPROP 1 LAST BODY_TYPE PLUMBING
J 0
(-5975 3500);
DISPLAY 1.234043 (-5975 3500);
PAINT GREEN (-5975 3500);
DISPLAY INVISIBLE (-5975 3500);
FORCEPROP 1 LAST HDL_TAP TRUE
J 0
(-5650 3425);
DISPLAY 1.234043 (-5650 3425);
PAINT GREEN (-5650 3425);
DISPLAY INVISIBLE (-5650 3425);
FORCEPROP 1 LAST PATH I102
J 0
(-5977 3550);
DISPLAY 0.872340 (-5977 3550);
PAINT GREEN (-5977 3550);
DISPLAY INVISIBLE (-5977 3550);
FORCEADD TAP..6
(-5975 3600);
FORCEPROP 3 LASTPIN (-5925 3600) SIG_NAME M_H_MA<2>
J 0
(-5915 3610);
DISPLAY 0.659574 (-5915 3610);
PAINT MONO (-5915 3610);
DISPLAY INVISIBLE (-5915 3610);
FORCEPROP 1 LASTPIN (-5925 3600) BN 2
J 0
(-5975 3610);
DISPLAY 0.617021 (-5975 3610);
PAINT PINK (-5975 3610);
FORCEPROP 2 LAST CDS_LIB mstr_standard
J 2
(-5975 3600);
DISPLAY 0.787234 (-5975 3600);
PAINT MONO (-5975 3600);
DISPLAY INVISIBLE (-5975 3600);
FORCEPROP 1 LAST BODY_TYPE PLUMBING
J 0
(-5975 3550);
DISPLAY 1.234043 (-5975 3550);
PAINT GREEN (-5975 3550);
DISPLAY INVISIBLE (-5975 3550);
FORCEPROP 1 LAST HDL_TAP TRUE
J 0
(-5650 3475);
DISPLAY 1.234043 (-5650 3475);
PAINT GREEN (-5650 3475);
DISPLAY INVISIBLE (-5650 3475);
FORCEPROP 1 LAST PATH I103
J 0
(-5977 3600);
DISPLAY 0.872340 (-5977 3600);
PAINT GREEN (-5977 3600);
DISPLAY INVISIBLE (-5977 3600);
FORCEADD TAP..6
(-5975 3650);
FORCEPROP 3 LASTPIN (-5925 3650) SIG_NAME M_H_MA<3>
J 0
(-5915 3660);
DISPLAY 0.659574 (-5915 3660);
PAINT MONO (-5915 3660);
DISPLAY INVISIBLE (-5915 3660);
FORCEPROP 1 LASTPIN (-5925 3650) BN 3
J 0
(-5975 3660);
DISPLAY 0.617021 (-5975 3660);
PAINT PINK (-5975 3660);
FORCEPROP 2 LAST CDS_LIB mstr_standard
J 2
(-5975 3650);
DISPLAY 0.787234 (-5975 3650);
PAINT MONO (-5975 3650);
DISPLAY INVISIBLE (-5975 3650);
FORCEPROP 1 LAST BODY_TYPE PLUMBING
J 0
(-5975 3600);
DISPLAY 1.234043 (-5975 3600);
PAINT GREEN (-5975 3600);
DISPLAY INVISIBLE (-5975 3600);
FORCEPROP 1 LAST HDL_TAP TRUE
J 0
(-5650 3525);
DISPLAY 1.234043 (-5650 3525);
PAINT GREEN (-5650 3525);
DISPLAY INVISIBLE (-5650 3525);
FORCEPROP 1 LAST PATH I104
J 0
(-5977 3650);
DISPLAY 0.872340 (-5977 3650);
PAINT GREEN (-5977 3650);
DISPLAY INVISIBLE (-5977 3650);
FORCEADD TAP..6
(-5975 3750);
FORCEPROP 3 LASTPIN (-5925 3750) SIG_NAME M_H_MA<5>
J 0
(-5915 3760);
DISPLAY 0.659574 (-5915 3760);
PAINT MONO (-5915 3760);
DISPLAY INVISIBLE (-5915 3760);
FORCEPROP 1 LASTPIN (-5925 3750) BN 5
J 0
(-5975 3760);
DISPLAY 0.617021 (-5975 3760);
PAINT PINK (-5975 3760);
FORCEPROP 2 LAST CDS_LIB mstr_standard
J 2
(-5975 3750);
DISPLAY 0.787234 (-5975 3750);
PAINT MONO (-5975 3750);
DISPLAY INVISIBLE (-5975 3750);
FORCEPROP 1 LAST BODY_TYPE PLUMBING
J 0
(-5975 3700);
DISPLAY 1.234043 (-5975 3700);
PAINT GREEN (-5975 3700);
DISPLAY INVISIBLE (-5975 3700);
FORCEPROP 1 LAST HDL_TAP TRUE
J 0
(-5650 3625);
DISPLAY 1.234043 (-5650 3625);
PAINT GREEN (-5650 3625);
DISPLAY INVISIBLE (-5650 3625);
FORCEPROP 1 LAST PATH I105
J 0
(-5977 3750);
DISPLAY 0.872340 (-5977 3750);
PAINT GREEN (-5977 3750);
DISPLAY INVISIBLE (-5977 3750);
FORCEADD TAP..6
(-5975 3700);
FORCEPROP 3 LASTPIN (-5925 3700) SIG_NAME M_H_MA<4>
J 0
(-5915 3710);
DISPLAY 0.659574 (-5915 3710);
PAINT MONO (-5915 3710);
DISPLAY INVISIBLE (-5915 3710);
FORCEPROP 1 LASTPIN (-5925 3700) BN 4
J 0
(-5975 3710);
DISPLAY 0.617021 (-5975 3710);
PAINT PINK (-5975 3710);
FORCEPROP 2 LAST CDS_LIB mstr_standard
J 2
(-5975 3700);
DISPLAY 0.787234 (-5975 3700);
PAINT MONO (-5975 3700);
DISPLAY INVISIBLE (-5975 3700);
FORCEPROP 1 LAST BODY_TYPE PLUMBING
J 0
(-5975 3650);
DISPLAY 1.234043 (-5975 3650);
PAINT GREEN (-5975 3650);
DISPLAY INVISIBLE (-5975 3650);
FORCEPROP 1 LAST HDL_TAP TRUE
J 0
(-5650 3575);
DISPLAY 1.234043 (-5650 3575);
PAINT GREEN (-5650 3575);
DISPLAY INVISIBLE (-5650 3575);
FORCEPROP 1 LAST PATH I106
J 0
(-5977 3700);
DISPLAY 0.872340 (-5977 3700);
PAINT GREEN (-5977 3700);
DISPLAY INVISIBLE (-5977 3700);
FORCEADD TAP..6
(-5975 3800);
FORCEPROP 3 LASTPIN (-5925 3800) SIG_NAME M_H_MA<6>
J 0
(-5915 3810);
DISPLAY 0.659574 (-5915 3810);
PAINT MONO (-5915 3810);
DISPLAY INVISIBLE (-5915 3810);
FORCEPROP 1 LASTPIN (-5925 3800) BN 6
J 0
(-5975 3810);
DISPLAY 0.617021 (-5975 3810);
PAINT PINK (-5975 3810);
FORCEPROP 2 LAST CDS_LIB mstr_standard
J 2
(-5975 3800);
DISPLAY 0.787234 (-5975 3800);
PAINT MONO (-5975 3800);
DISPLAY INVISIBLE (-5975 3800);
FORCEPROP 1 LAST BODY_TYPE PLUMBING
J 0
(-5975 3750);
DISPLAY 1.234043 (-5975 3750);
PAINT GREEN (-5975 3750);
DISPLAY INVISIBLE (-5975 3750);
FORCEPROP 1 LAST HDL_TAP TRUE
J 0
(-5650 3675);
DISPLAY 1.234043 (-5650 3675);
PAINT GREEN (-5650 3675);
DISPLAY INVISIBLE (-5650 3675);
FORCEPROP 1 LAST PATH I107
J 0
(-5977 3800);
DISPLAY 0.872340 (-5977 3800);
PAINT GREEN (-5977 3800);
DISPLAY INVISIBLE (-5977 3800);
FORCEADD TAP..6
(-5975 3900);
FORCEPROP 3 LASTPIN (-5925 3900) SIG_NAME M_H_MA<8>
J 0
(-5915 3910);
DISPLAY 0.659574 (-5915 3910);
PAINT MONO (-5915 3910);
DISPLAY INVISIBLE (-5915 3910);
FORCEPROP 1 LASTPIN (-5925 3900) BN 8
J 0
(-5975 3910);
DISPLAY 0.617021 (-5975 3910);
PAINT PINK (-5975 3910);
FORCEPROP 2 LAST CDS_LIB mstr_standard
J 2
(-5975 3900);
DISPLAY 0.787234 (-5975 3900);
PAINT MONO (-5975 3900);
DISPLAY INVISIBLE (-5975 3900);
FORCEPROP 1 LAST BODY_TYPE PLUMBING
J 0
(-5975 3850);
DISPLAY 1.234043 (-5975 3850);
PAINT GREEN (-5975 3850);
DISPLAY INVISIBLE (-5975 3850);
FORCEPROP 1 LAST HDL_TAP TRUE
J 0
(-5650 3775);
DISPLAY 1.234043 (-5650 3775);
PAINT GREEN (-5650 3775);
DISPLAY INVISIBLE (-5650 3775);
FORCEPROP 1 LAST PATH I108
J 0
(-5977 3900);
DISPLAY 0.872340 (-5977 3900);
PAINT GREEN (-5977 3900);
DISPLAY INVISIBLE (-5977 3900);
FORCEADD TAP..6
(-5975 3850);
FORCEPROP 3 LASTPIN (-5925 3850) SIG_NAME M_H_MA<7>
J 0
(-5915 3860);
DISPLAY 0.659574 (-5915 3860);
PAINT MONO (-5915 3860);
DISPLAY INVISIBLE (-5915 3860);
FORCEPROP 1 LASTPIN (-5925 3850) BN 7
J 0
(-5975 3860);
DISPLAY 0.617021 (-5975 3860);
PAINT PINK (-5975 3860);
FORCEPROP 2 LAST CDS_LIB mstr_standard
J 2
(-5975 3850);
DISPLAY 0.787234 (-5975 3850);
PAINT MONO (-5975 3850);
DISPLAY INVISIBLE (-5975 3850);
FORCEPROP 1 LAST BODY_TYPE PLUMBING
J 0
(-5975 3800);
DISPLAY 1.234043 (-5975 3800);
PAINT GREEN (-5975 3800);
DISPLAY INVISIBLE (-5975 3800);
FORCEPROP 1 LAST HDL_TAP TRUE
J 0
(-5650 3725);
DISPLAY 1.234043 (-5650 3725);
PAINT GREEN (-5650 3725);
DISPLAY INVISIBLE (-5650 3725);
FORCEPROP 1 LAST PATH I109
J 0
(-5977 3850);
DISPLAY 0.872340 (-5977 3850);
PAINT GREEN (-5977 3850);
DISPLAY INVISIBLE (-5977 3850);
FORCEADD OFFPAGE..5
(-6950 2050);
FORCEPROP 2 LAST $XR0 43 
J 0
(-7174 2050);
DISPLAY 0.638298 (-7174 2050);
PAINT MONO (-7174 2050);
FORCEPROP 2 LAST $XR1 44 
J 0
(-7264 2050);
DISPLAY 0.638298 (-7264 2050);
PAINT MONO (-7264 2050);
FORCEPROP 2 LAST $XR2 45 
J 0
(-7354 2050);
DISPLAY 0.638298 (-7354 2050);
PAINT MONO (-7354 2050);
FORCEPROP 2 LAST $XR3 46 
J 0
(-7444 2050);
DISPLAY 0.638298 (-7444 2050);
PAINT MONO (-7444 2050);
FORCEPROP 2 LAST $XR4 47 
J 0
(-7534 2050);
DISPLAY 0.638298 (-7534 2050);
PAINT MONO (-7534 2050);
FORCEPROP 2 LAST $XR5 48 
J 0
(-7624 2050);
DISPLAY 0.638298 (-7624 2050);
PAINT MONO (-7624 2050);
FORCEPROP 2 LAST $XR6 49 
J 0
(-7714 2050);
DISPLAY 0.638298 (-7714 2050);
PAINT MONO (-7714 2050);
FORCEPROP 2 LAST $XR7 50 
J 0
(-7804 2050);
DISPLAY 0.638298 (-7804 2050);
PAINT MONO (-7804 2050);
FORCEPROP 2 LAST $XR8 51 
J 0
(-7894 2050);
DISPLAY 0.638298 (-7894 2050);
PAINT MONO (-7894 2050);
FORCEPROP 2 LAST $XR9 52 
J 0
(-7984 2050);
DISPLAY 0.638298 (-7984 2050);
PAINT MONO (-7984 2050);
FORCEPROP 2 LAST $XR10 53 
J 0
(-7174 2014);
DISPLAY 0.638298 (-7174 2014);
PAINT MONO (-7174 2014);
FORCEPROP 2 LAST $XR11 54 
J 0
(-7264 2014);
DISPLAY 0.638298 (-7264 2014);
PAINT MONO (-7264 2014);
FORCEPROP 2 LAST $XR12 77 
J 0
(-7354 2014);
DISPLAY 0.638298 (-7354 2014);
PAINT MONO (-7354 2014);
FORCEPROP 2 LAST $XR13 78 
J 0
(-7444 2014);
DISPLAY 0.638298 (-7444 2014);
PAINT MONO (-7444 2014);
FORCEPROP 2 LAST $XR14 79 
J 0
(-7534 2014);
DISPLAY 0.638298 (-7534 2014);
PAINT MONO (-7534 2014);
FORCEPROP 2 LAST $XR15 81 
J 0
(-7624 2014);
DISPLAY 0.638298 (-7624 2014);
PAINT MONO (-7624 2014);
FORCEPROP 2 LAST $XR16 82 
J 0
(-7714 2014);
DISPLAY 0.638298 (-7714 2014);
PAINT MONO (-7714 2014);
FORCEPROP 2 LAST $XR17 83 
J 0
(-7804 2014);
DISPLAY 0.638298 (-7804 2014);
PAINT MONO (-7804 2014);
FORCEPROP 2 LAST $XR18 84 
J 0
(-7894 2014);
DISPLAY 0.638298 (-7894 2014);
PAINT MONO (-7894 2014);
FORCEPROP 2 LAST $XR19 85 
J 0
(-7984 2014);
DISPLAY 0.638298 (-7984 2014);
PAINT MONO (-7984 2014);
FORCEPROP 2 LAST $XR20 86 
J 0
(-7174 2086);
DISPLAY 0.638298 (-7174 2086);
PAINT MONO (-7174 2086);
FORCEPROP 2 LAST $XR21 87 
J 0
(-7264 2086);
DISPLAY 0.638298 (-7264 2086);
PAINT MONO (-7264 2086);
FORCEPROP 2 LAST $XR22 88 
J 0
(-7354 2086);
DISPLAY 0.638298 (-7354 2086);
PAINT MONO (-7354 2086);
FORCEPROP 2 LAST $XR23 94 
J 0
(-7444 2086);
DISPLAY 0.638298 (-7444 2086);
PAINT MONO (-7444 2086);
FORCEPROP 2 LAST CDS_LIB mstr_standard
J 0
(-6950 2050);
DISPLAY 0.787234 (-6950 2050);
PAINT MONO (-6950 2050);
DISPLAY INVISIBLE (-6950 2050);
FORCEPROP 1 LAST OFFPAGE TRUE
J 0
(-6625 1925);
DISPLAY 1.404255 (-6625 1925);
PAINT GREEN (-6625 1925);
DISPLAY INVISIBLE (-6625 1925);
FORCEPROP 1 LAST COMMENT_BODY TRUE
J 0
(-6850 1975);
DISPLAY 1.404255 (-6850 1975);
PAINT GREEN (-6850 1975);
DISPLAY INVISIBLE (-6850 1975);
FORCEPROP 2 LAST PATH I11
J 0
(-7200 2100);
DISPLAY 1.021277 (-7200 2100);
PAINT ORANGE (-7200 2100);
DISPLAY INVISIBLE (-7200 2100);
FORCEADD TAP..6
(-5975 4000);
FORCEPROP 3 LASTPIN (-5925 4000) SIG_NAME M_H_MA<10>
J 0
(-5915 4010);
DISPLAY 0.659574 (-5915 4010);
PAINT MONO (-5915 4010);
DISPLAY INVISIBLE (-5915 4010);
FORCEPROP 1 LASTPIN (-5925 4000) BN 10
J 0
(-5975 4010);
DISPLAY 0.617021 (-5975 4010);
PAINT PINK (-5975 4010);
FORCEPROP 2 LAST CDS_LIB mstr_standard
J 2
(-5975 4000);
DISPLAY 0.787234 (-5975 4000);
PAINT MONO (-5975 4000);
DISPLAY INVISIBLE (-5975 4000);
FORCEPROP 1 LAST BODY_TYPE PLUMBING
J 0
(-5975 3950);
DISPLAY 1.234043 (-5975 3950);
PAINT GREEN (-5975 3950);
DISPLAY INVISIBLE (-5975 3950);
FORCEPROP 1 LAST HDL_TAP TRUE
J 0
(-5650 3875);
DISPLAY 1.234043 (-5650 3875);
PAINT GREEN (-5650 3875);
DISPLAY INVISIBLE (-5650 3875);
FORCEPROP 1 LAST PATH I110
J 0
(-5977 4000);
DISPLAY 0.872340 (-5977 4000);
PAINT GREEN (-5977 4000);
DISPLAY INVISIBLE (-5977 4000);
FORCEADD TAP..6
(-5975 3950);
FORCEPROP 3 LASTPIN (-5925 3950) SIG_NAME M_H_MA<9>
J 0
(-5915 3960);
DISPLAY 0.659574 (-5915 3960);
PAINT MONO (-5915 3960);
DISPLAY INVISIBLE (-5915 3960);
FORCEPROP 1 LASTPIN (-5925 3950) BN 9
J 0
(-5975 3960);
DISPLAY 0.617021 (-5975 3960);
PAINT PINK (-5975 3960);
FORCEPROP 2 LAST CDS_LIB mstr_standard
J 2
(-5975 3950);
DISPLAY 0.787234 (-5975 3950);
PAINT MONO (-5975 3950);
DISPLAY INVISIBLE (-5975 3950);
FORCEPROP 1 LAST BODY_TYPE PLUMBING
J 0
(-5975 3900);
DISPLAY 1.234043 (-5975 3900);
PAINT GREEN (-5975 3900);
DISPLAY INVISIBLE (-5975 3900);
FORCEPROP 1 LAST HDL_TAP TRUE
J 0
(-5650 3825);
DISPLAY 1.234043 (-5650 3825);
PAINT GREEN (-5650 3825);
DISPLAY INVISIBLE (-5650 3825);
FORCEPROP 1 LAST PATH I111
J 0
(-5977 3950);
DISPLAY 0.872340 (-5977 3950);
PAINT GREEN (-5977 3950);
DISPLAY INVISIBLE (-5977 3950);
FORCEADD TAP..6
(-5975 4050);
FORCEPROP 3 LASTPIN (-5925 4050) SIG_NAME M_H_MA<11>
J 0
(-5915 4060);
DISPLAY 0.659574 (-5915 4060);
PAINT MONO (-5915 4060);
DISPLAY INVISIBLE (-5915 4060);
FORCEPROP 1 LASTPIN (-5925 4050) BN 11
J 0
(-5975 4060);
DISPLAY 0.617021 (-5975 4060);
PAINT PINK (-5975 4060);
FORCEPROP 2 LAST CDS_LIB mstr_standard
J 2
(-5975 4050);
DISPLAY 0.787234 (-5975 4050);
PAINT MONO (-5975 4050);
DISPLAY INVISIBLE (-5975 4050);
FORCEPROP 1 LAST BODY_TYPE PLUMBING
J 0
(-5975 4000);
DISPLAY 1.234043 (-5975 4000);
PAINT GREEN (-5975 4000);
DISPLAY INVISIBLE (-5975 4000);
FORCEPROP 1 LAST HDL_TAP TRUE
J 0
(-5650 3925);
DISPLAY 1.234043 (-5650 3925);
PAINT GREEN (-5650 3925);
DISPLAY INVISIBLE (-5650 3925);
FORCEPROP 1 LAST PATH I112
J 0
(-5977 4050);
DISPLAY 0.872340 (-5977 4050);
PAINT GREEN (-5977 4050);
DISPLAY INVISIBLE (-5977 4050);
FORCEADD TAP..6
(-5975 4100);
FORCEPROP 3 LASTPIN (-5925 4100) SIG_NAME M_H_MA<12>
J 0
(-5915 4110);
DISPLAY 0.659574 (-5915 4110);
PAINT MONO (-5915 4110);
DISPLAY INVISIBLE (-5915 4110);
FORCEPROP 1 LASTPIN (-5925 4100) BN 12
J 0
(-5975 4110);
DISPLAY 0.617021 (-5975 4110);
PAINT PINK (-5975 4110);
FORCEPROP 2 LAST CDS_LIB mstr_standard
J 2
(-5975 4100);
DISPLAY 0.787234 (-5975 4100);
PAINT MONO (-5975 4100);
DISPLAY INVISIBLE (-5975 4100);
FORCEPROP 1 LAST BODY_TYPE PLUMBING
J 0
(-5975 4050);
DISPLAY 1.234043 (-5975 4050);
PAINT GREEN (-5975 4050);
DISPLAY INVISIBLE (-5975 4050);
FORCEPROP 1 LAST HDL_TAP TRUE
J 0
(-5650 3975);
DISPLAY 1.234043 (-5650 3975);
PAINT GREEN (-5650 3975);
DISPLAY INVISIBLE (-5650 3975);
FORCEPROP 1 LAST PATH I113
J 0
(-5977 4100);
DISPLAY 0.872340 (-5977 4100);
PAINT GREEN (-5977 4100);
DISPLAY INVISIBLE (-5977 4100);
FORCEADD TAP..6
(-5975 4150);
FORCEPROP 3 LASTPIN (-5925 4150) SIG_NAME M_H_MA<13>
J 0
(-5915 4160);
DISPLAY 0.659574 (-5915 4160);
PAINT MONO (-5915 4160);
DISPLAY INVISIBLE (-5915 4160);
FORCEPROP 1 LASTPIN (-5925 4150) BN 13
J 0
(-5975 4160);
DISPLAY 0.617021 (-5975 4160);
PAINT PINK (-5975 4160);
FORCEPROP 2 LAST CDS_LIB mstr_standard
J 2
(-5975 4150);
DISPLAY 0.787234 (-5975 4150);
PAINT MONO (-5975 4150);
DISPLAY INVISIBLE (-5975 4150);
FORCEPROP 1 LAST BODY_TYPE PLUMBING
J 0
(-5975 4100);
DISPLAY 1.234043 (-5975 4100);
PAINT GREEN (-5975 4100);
DISPLAY INVISIBLE (-5975 4100);
FORCEPROP 1 LAST HDL_TAP TRUE
J 0
(-5650 4025);
DISPLAY 1.234043 (-5650 4025);
PAINT GREEN (-5650 4025);
DISPLAY INVISIBLE (-5650 4025);
FORCEPROP 1 LAST PATH I114
J 0
(-5977 4150);
DISPLAY 0.872340 (-5977 4150);
PAINT GREEN (-5977 4150);
DISPLAY INVISIBLE (-5977 4150);
FORCEADD TAP..6
(-5975 4250);
FORCEPROP 3 LASTPIN (-5925 4250) SIG_NAME M_H_MA<15>
J 0
(-5915 4260);
DISPLAY 0.659574 (-5915 4260);
PAINT MONO (-5915 4260);
DISPLAY INVISIBLE (-5915 4260);
FORCEPROP 1 LASTPIN (-5925 4250) BN 15
J 0
(-5975 4260);
DISPLAY 0.617021 (-5975 4260);
PAINT PINK (-5975 4260);
FORCEPROP 2 LAST CDS_LIB mstr_standard
J 2
(-5975 4250);
DISPLAY 0.787234 (-5975 4250);
PAINT MONO (-5975 4250);
DISPLAY INVISIBLE (-5975 4250);
FORCEPROP 1 LAST BODY_TYPE PLUMBING
J 0
(-5975 4200);
DISPLAY 1.234043 (-5975 4200);
PAINT GREEN (-5975 4200);
DISPLAY INVISIBLE (-5975 4200);
FORCEPROP 1 LAST HDL_TAP TRUE
J 0
(-5650 4125);
DISPLAY 1.234043 (-5650 4125);
PAINT GREEN (-5650 4125);
DISPLAY INVISIBLE (-5650 4125);
FORCEPROP 1 LAST PATH I115
J 0
(-5977 4250);
DISPLAY 0.872340 (-5977 4250);
PAINT GREEN (-5977 4250);
DISPLAY INVISIBLE (-5977 4250);
FORCEADD TAP..6
(-5975 4200);
FORCEPROP 3 LASTPIN (-5925 4200) SIG_NAME M_H_MA<14>
J 0
(-5915 4210);
DISPLAY 0.659574 (-5915 4210);
PAINT MONO (-5915 4210);
DISPLAY INVISIBLE (-5915 4210);
FORCEPROP 1 LASTPIN (-5925 4200) BN 14
J 0
(-5975 4210);
DISPLAY 0.617021 (-5975 4210);
PAINT PINK (-5975 4210);
FORCEPROP 2 LAST CDS_LIB mstr_standard
J 2
(-5975 4200);
DISPLAY 0.787234 (-5975 4200);
PAINT MONO (-5975 4200);
DISPLAY INVISIBLE (-5975 4200);
FORCEPROP 1 LAST BODY_TYPE PLUMBING
J 0
(-5975 4150);
DISPLAY 1.234043 (-5975 4150);
PAINT GREEN (-5975 4150);
DISPLAY INVISIBLE (-5975 4150);
FORCEPROP 1 LAST HDL_TAP TRUE
J 0
(-5650 4075);
DISPLAY 1.234043 (-5650 4075);
PAINT GREEN (-5650 4075);
DISPLAY INVISIBLE (-5650 4075);
FORCEPROP 1 LAST PATH I116
J 0
(-5977 4200);
DISPLAY 0.872340 (-5977 4200);
PAINT GREEN (-5977 4200);
DISPLAY INVISIBLE (-5977 4200);
FORCEADD TAP..6
(-5975 4300);
FORCEPROP 3 LASTPIN (-5925 4300) SIG_NAME M_H_MA<16>
J 0
(-5915 4310);
DISPLAY 0.659574 (-5915 4310);
PAINT MONO (-5915 4310);
DISPLAY INVISIBLE (-5915 4310);
FORCEPROP 1 LASTPIN (-5925 4300) BN 16
J 0
(-5975 4310);
DISPLAY 0.617021 (-5975 4310);
PAINT PINK (-5975 4310);
FORCEPROP 2 LAST CDS_LIB mstr_standard
J 2
(-5975 4300);
DISPLAY 0.787234 (-5975 4300);
PAINT MONO (-5975 4300);
DISPLAY INVISIBLE (-5975 4300);
FORCEPROP 1 LAST BODY_TYPE PLUMBING
J 0
(-5975 4250);
DISPLAY 1.234043 (-5975 4250);
PAINT GREEN (-5975 4250);
DISPLAY INVISIBLE (-5975 4250);
FORCEPROP 1 LAST HDL_TAP TRUE
J 0
(-5650 4175);
DISPLAY 1.234043 (-5650 4175);
PAINT GREEN (-5650 4175);
DISPLAY INVISIBLE (-5650 4175);
FORCEPROP 1 LAST PATH I117
J 0
(-5977 4300);
DISPLAY 0.872340 (-5977 4300);
PAINT GREEN (-5977 4300);
DISPLAY INVISIBLE (-5977 4300);
FORCEADD TAP..6
(-5975 4350);
FORCEPROP 3 LASTPIN (-5925 4350) SIG_NAME M_H_MA<17>
J 0
(-5915 4360);
DISPLAY 0.659574 (-5915 4360);
PAINT MONO (-5915 4360);
DISPLAY INVISIBLE (-5915 4360);
FORCEPROP 1 LASTPIN (-5925 4350) BN 17
J 0
(-5975 4360);
DISPLAY 0.617021 (-5975 4360);
PAINT PINK (-5975 4360);
FORCEPROP 2 LAST CDS_LIB mstr_standard
J 0
(-5975 4350);
DISPLAY 0.787234 (-5975 4350);
PAINT MONO (-5975 4350);
DISPLAY INVISIBLE (-5975 4350);
FORCEPROP 1 LAST BODY_TYPE PLUMBING
J 0
(-5975 4300);
DISPLAY 1.234043 (-5975 4300);
PAINT GREEN (-5975 4300);
DISPLAY INVISIBLE (-5975 4300);
FORCEPROP 1 LAST HDL_TAP TRUE
J 0
(-5650 4225);
DISPLAY 1.234043 (-5650 4225);
PAINT GREEN (-5650 4225);
DISPLAY INVISIBLE (-5650 4225);
FORCEPROP 1 LAST PATH I118
J 0
(-5977 4350);
DISPLAY 0.872340 (-5977 4350);
PAINT GREEN (-5977 4350);
DISPLAY INVISIBLE (-5977 4350);
FORCEADD TAP..6
R 2
(-4475 3550);
FORCEPROP 3 LASTPIN (-4525 3550) SIG_NAME M_H_DQ<47>
J 0
(-4515 3560);
DISPLAY 0.659574 (-4515 3560);
PAINT MONO (-4515 3560);
DISPLAY INVISIBLE (-4515 3560);
FORCEPROP 1 LASTPIN (-4525 3550) BN 47
J 2
(-4475 3560);
DISPLAY 0.617021 (-4475 3560);
PAINT PINK (-4475 3560);
FORCEPROP 2 LAST CDS_LIB mstr_standard
J 2
(-4475 3550);
DISPLAY 0.787234 (-4475 3550);
PAINT MONO (-4475 3550);
DISPLAY INVISIBLE (-4475 3550);
FORCEPROP 1 LAST BODY_TYPE PLUMBING
J 2
(-4475 3500);
DISPLAY 1.234043 (-4475 3500);
PAINT GREEN (-4475 3500);
DISPLAY INVISIBLE (-4475 3500);
FORCEPROP 1 LAST HDL_TAP TRUE
J 2
(-4800 3425);
DISPLAY 1.234043 (-4800 3425);
PAINT GREEN (-4800 3425);
DISPLAY INVISIBLE (-4800 3425);
FORCEPROP 1 LAST PATH I119
J 2
(-4473 3550);
DISPLAY 0.872340 (-4473 3550);
PAINT GREEN (-4473 3550);
DISPLAY INVISIBLE (-4473 3550);
FORCEADD OFFPAGE..1
(-6625 2250);
FORCEPROP 2 LAST $XR0 55 
J 0
(-6846 2250);
DISPLAY 0.638298 (-6846 2250);
PAINT MONO (-6846 2250);
FORCEPROP 2 LAST $XR1 77 
J 0
(-6936 2250);
DISPLAY 0.638298 (-6936 2250);
PAINT MONO (-6936 2250);
FORCEPROP 2 LAST $XR2 78 
J 0
(-7026 2250);
DISPLAY 0.638298 (-7026 2250);
PAINT MONO (-7026 2250);
FORCEPROP 2 LAST $XR3 79 
J 0
(-7116 2250);
DISPLAY 0.638298 (-7116 2250);
PAINT MONO (-7116 2250);
FORCEPROP 2 LAST $XR4 81 
J 0
(-7206 2250);
DISPLAY 0.638298 (-7206 2250);
PAINT MONO (-7206 2250);
FORCEPROP 2 LAST $XR5 82 
J 0
(-7296 2250);
DISPLAY 0.638298 (-7296 2250);
PAINT MONO (-7296 2250);
FORCEPROP 2 LAST CDS_LIB mstr_standard
J 0
(-6625 2250);
DISPLAY 0.787234 (-6625 2250);
PAINT MONO (-6625 2250);
DISPLAY INVISIBLE (-6625 2250);
FORCEPROP 1 LAST OFFPAGE TRUE
J 0
(-6300 2125);
DISPLAY 0.936170 (-6300 2125);
PAINT GREEN (-6300 2125);
DISPLAY INVISIBLE (-6300 2125);
FORCEPROP 1 LAST COMMENT_BODY TRUE
J 0
(-6500 2150);
DISPLAY 0.936170 (-6500 2150);
PAINT GREEN (-6500 2150);
DISPLAY INVISIBLE (-6500 2150);
FORCEPROP 2 LAST PATH I12
J 0
(-6875 2300);
DISPLAY 1.021277 (-6875 2300);
PAINT ORANGE (-6875 2300);
DISPLAY INVISIBLE (-6875 2300);
FORCEADD TAP..6
R 2
(-4475 3600);
FORCEPROP 3 LASTPIN (-4525 3600) SIG_NAME M_H_DQ<48>
J 0
(-4515 3610);
DISPLAY 0.659574 (-4515 3610);
PAINT MONO (-4515 3610);
DISPLAY INVISIBLE (-4515 3610);
FORCEPROP 1 LASTPIN (-4525 3600) BN 48
J 2
(-4475 3610);
DISPLAY 0.617021 (-4475 3610);
PAINT PINK (-4475 3610);
FORCEPROP 2 LAST CDS_LIB mstr_standard
J 2
(-4475 3600);
DISPLAY 0.787234 (-4475 3600);
PAINT MONO (-4475 3600);
DISPLAY INVISIBLE (-4475 3600);
FORCEPROP 1 LAST BODY_TYPE PLUMBING
J 2
(-4475 3550);
DISPLAY 1.234043 (-4475 3550);
PAINT GREEN (-4475 3550);
DISPLAY INVISIBLE (-4475 3550);
FORCEPROP 1 LAST HDL_TAP TRUE
J 2
(-4800 3475);
DISPLAY 1.234043 (-4800 3475);
PAINT GREEN (-4800 3475);
DISPLAY INVISIBLE (-4800 3475);
FORCEPROP 1 LAST PATH I120
J 2
(-4473 3600);
DISPLAY 0.872340 (-4473 3600);
PAINT GREEN (-4473 3600);
DISPLAY INVISIBLE (-4473 3600);
FORCEADD TAP..6
R 2
(-4475 3650);
FORCEPROP 3 LASTPIN (-4525 3650) SIG_NAME M_H_DQ<49>
J 0
(-4515 3660);
DISPLAY 0.659574 (-4515 3660);
PAINT MONO (-4515 3660);
DISPLAY INVISIBLE (-4515 3660);
FORCEPROP 1 LASTPIN (-4525 3650) BN 49
J 2
(-4475 3660);
DISPLAY 0.617021 (-4475 3660);
PAINT PINK (-4475 3660);
FORCEPROP 2 LAST CDS_LIB mstr_standard
J 2
(-4475 3650);
DISPLAY 0.787234 (-4475 3650);
PAINT MONO (-4475 3650);
DISPLAY INVISIBLE (-4475 3650);
FORCEPROP 1 LAST BODY_TYPE PLUMBING
J 2
(-4475 3600);
DISPLAY 1.234043 (-4475 3600);
PAINT GREEN (-4475 3600);
DISPLAY INVISIBLE (-4475 3600);
FORCEPROP 1 LAST HDL_TAP TRUE
J 2
(-4800 3525);
DISPLAY 1.234043 (-4800 3525);
PAINT GREEN (-4800 3525);
DISPLAY INVISIBLE (-4800 3525);
FORCEPROP 1 LAST PATH I121
J 2
(-4473 3650);
DISPLAY 0.872340 (-4473 3650);
PAINT GREEN (-4473 3650);
DISPLAY INVISIBLE (-4473 3650);
FORCEADD TAP..6
R 2
(-4475 3800);
FORCEPROP 3 LASTPIN (-4525 3800) SIG_NAME M_H_DQ<52>
J 0
(-4515 3810);
DISPLAY 0.659574 (-4515 3810);
PAINT MONO (-4515 3810);
DISPLAY INVISIBLE (-4515 3810);
FORCEPROP 1 LASTPIN (-4525 3800) BN 52
J 2
(-4475 3810);
DISPLAY 0.617021 (-4475 3810);
PAINT PINK (-4475 3810);
FORCEPROP 2 LAST CDS_LIB mstr_standard
J 2
(-4475 3800);
DISPLAY 0.787234 (-4475 3800);
PAINT MONO (-4475 3800);
DISPLAY INVISIBLE (-4475 3800);
FORCEPROP 1 LAST BODY_TYPE PLUMBING
J 2
(-4475 3750);
DISPLAY 1.234043 (-4475 3750);
PAINT GREEN (-4475 3750);
DISPLAY INVISIBLE (-4475 3750);
FORCEPROP 1 LAST HDL_TAP TRUE
J 2
(-4800 3675);
DISPLAY 1.234043 (-4800 3675);
PAINT GREEN (-4800 3675);
DISPLAY INVISIBLE (-4800 3675);
FORCEPROP 1 LAST PATH I122
J 2
(-4473 3800);
DISPLAY 0.872340 (-4473 3800);
PAINT GREEN (-4473 3800);
DISPLAY INVISIBLE (-4473 3800);
FORCEADD TAP..6
R 2
(-4475 3700);
FORCEPROP 3 LASTPIN (-4525 3700) SIG_NAME M_H_DQ<50>
J 0
(-4515 3710);
DISPLAY 0.659574 (-4515 3710);
PAINT MONO (-4515 3710);
DISPLAY INVISIBLE (-4515 3710);
FORCEPROP 1 LASTPIN (-4525 3700) BN 50
J 2
(-4475 3710);
DISPLAY 0.617021 (-4475 3710);
PAINT PINK (-4475 3710);
FORCEPROP 2 LAST CDS_LIB mstr_standard
J 2
(-4475 3700);
DISPLAY 0.787234 (-4475 3700);
PAINT MONO (-4475 3700);
DISPLAY INVISIBLE (-4475 3700);
FORCEPROP 1 LAST BODY_TYPE PLUMBING
J 2
(-4475 3650);
DISPLAY 1.234043 (-4475 3650);
PAINT GREEN (-4475 3650);
DISPLAY INVISIBLE (-4475 3650);
FORCEPROP 1 LAST HDL_TAP TRUE
J 2
(-4800 3575);
DISPLAY 1.234043 (-4800 3575);
PAINT GREEN (-4800 3575);
DISPLAY INVISIBLE (-4800 3575);
FORCEPROP 1 LAST PATH I123
J 2
(-4473 3700);
DISPLAY 0.872340 (-4473 3700);
PAINT GREEN (-4473 3700);
DISPLAY INVISIBLE (-4473 3700);
FORCEADD TAP..6
R 2
(-4475 3750);
FORCEPROP 3 LASTPIN (-4525 3750) SIG_NAME M_H_DQ<51>
J 0
(-4515 3760);
DISPLAY 0.659574 (-4515 3760);
PAINT MONO (-4515 3760);
DISPLAY INVISIBLE (-4515 3760);
FORCEPROP 1 LASTPIN (-4525 3750) BN 51
J 2
(-4475 3760);
DISPLAY 0.617021 (-4475 3760);
PAINT PINK (-4475 3760);
FORCEPROP 2 LAST CDS_LIB mstr_standard
J 2
(-4475 3750);
DISPLAY 0.787234 (-4475 3750);
PAINT MONO (-4475 3750);
DISPLAY INVISIBLE (-4475 3750);
FORCEPROP 1 LAST BODY_TYPE PLUMBING
J 2
(-4475 3700);
DISPLAY 1.234043 (-4475 3700);
PAINT GREEN (-4475 3700);
DISPLAY INVISIBLE (-4475 3700);
FORCEPROP 1 LAST HDL_TAP TRUE
J 2
(-4800 3625);
DISPLAY 1.234043 (-4800 3625);
PAINT GREEN (-4800 3625);
DISPLAY INVISIBLE (-4800 3625);
FORCEPROP 1 LAST PATH I124
J 2
(-4473 3750);
DISPLAY 0.872340 (-4473 3750);
PAINT GREEN (-4473 3750);
DISPLAY INVISIBLE (-4473 3750);
FORCEADD TAP..6
R 2
(-4475 3850);
FORCEPROP 3 LASTPIN (-4525 3850) SIG_NAME M_H_DQ<53>
J 0
(-4515 3860);
DISPLAY 0.659574 (-4515 3860);
PAINT MONO (-4515 3860);
DISPLAY INVISIBLE (-4515 3860);
FORCEPROP 1 LASTPIN (-4525 3850) BN 53
J 2
(-4475 3860);
DISPLAY 0.617021 (-4475 3860);
PAINT PINK (-4475 3860);
FORCEPROP 2 LAST CDS_LIB mstr_standard
J 2
(-4475 3850);
DISPLAY 0.787234 (-4475 3850);
PAINT MONO (-4475 3850);
DISPLAY INVISIBLE (-4475 3850);
FORCEPROP 1 LAST BODY_TYPE PLUMBING
J 2
(-4475 3800);
DISPLAY 1.234043 (-4475 3800);
PAINT GREEN (-4475 3800);
DISPLAY INVISIBLE (-4475 3800);
FORCEPROP 1 LAST HDL_TAP TRUE
J 2
(-4800 3725);
DISPLAY 1.234043 (-4800 3725);
PAINT GREEN (-4800 3725);
DISPLAY INVISIBLE (-4800 3725);
FORCEPROP 1 LAST PATH I125
J 2
(-4473 3850);
DISPLAY 0.872340 (-4473 3850);
PAINT GREEN (-4473 3850);
DISPLAY INVISIBLE (-4473 3850);
FORCEADD TAP..6
R 2
(-4475 3900);
FORCEPROP 3 LASTPIN (-4525 3900) SIG_NAME M_H_DQ<54>
J 0
(-4515 3910);
DISPLAY 0.659574 (-4515 3910);
PAINT MONO (-4515 3910);
DISPLAY INVISIBLE (-4515 3910);
FORCEPROP 1 LASTPIN (-4525 3900) BN 54
J 2
(-4475 3910);
DISPLAY 0.617021 (-4475 3910);
PAINT PINK (-4475 3910);
FORCEPROP 2 LAST CDS_LIB mstr_standard
J 2
(-4475 3900);
DISPLAY 0.787234 (-4475 3900);
PAINT MONO (-4475 3900);
DISPLAY INVISIBLE (-4475 3900);
FORCEPROP 1 LAST BODY_TYPE PLUMBING
J 2
(-4475 3850);
DISPLAY 1.234043 (-4475 3850);
PAINT GREEN (-4475 3850);
DISPLAY INVISIBLE (-4475 3850);
FORCEPROP 1 LAST HDL_TAP TRUE
J 2
(-4800 3775);
DISPLAY 1.234043 (-4800 3775);
PAINT GREEN (-4800 3775);
DISPLAY INVISIBLE (-4800 3775);
FORCEPROP 1 LAST PATH I126
J 2
(-4473 3900);
DISPLAY 0.872340 (-4473 3900);
PAINT GREEN (-4473 3900);
DISPLAY INVISIBLE (-4473 3900);
FORCEADD TAP..6
R 2
(-4475 4050);
FORCEPROP 3 LASTPIN (-4525 4050) SIG_NAME M_H_DQ<57>
J 0
(-4515 4060);
DISPLAY 0.659574 (-4515 4060);
PAINT MONO (-4515 4060);
DISPLAY INVISIBLE (-4515 4060);
FORCEPROP 1 LASTPIN (-4525 4050) BN 57
J 2
(-4475 4060);
DISPLAY 0.617021 (-4475 4060);
PAINT PINK (-4475 4060);
FORCEPROP 2 LAST CDS_LIB mstr_standard
J 2
(-4475 4050);
DISPLAY 0.787234 (-4475 4050);
PAINT MONO (-4475 4050);
DISPLAY INVISIBLE (-4475 4050);
FORCEPROP 1 LAST BODY_TYPE PLUMBING
J 2
(-4475 4000);
DISPLAY 1.234043 (-4475 4000);
PAINT GREEN (-4475 4000);
DISPLAY INVISIBLE (-4475 4000);
FORCEPROP 1 LAST HDL_TAP TRUE
J 2
(-4800 3925);
DISPLAY 1.234043 (-4800 3925);
PAINT GREEN (-4800 3925);
DISPLAY INVISIBLE (-4800 3925);
FORCEPROP 1 LAST PATH I127
J 2
(-4473 4050);
DISPLAY 0.872340 (-4473 4050);
PAINT GREEN (-4473 4050);
DISPLAY INVISIBLE (-4473 4050);
FORCEADD TAP..6
R 2
(-4475 3950);
FORCEPROP 3 LASTPIN (-4525 3950) SIG_NAME M_H_DQ<55>
J 0
(-4515 3960);
DISPLAY 0.659574 (-4515 3960);
PAINT MONO (-4515 3960);
DISPLAY INVISIBLE (-4515 3960);
FORCEPROP 1 LASTPIN (-4525 3950) BN 55
J 2
(-4475 3960);
DISPLAY 0.617021 (-4475 3960);
PAINT PINK (-4475 3960);
FORCEPROP 2 LAST CDS_LIB mstr_standard
J 2
(-4475 3950);
DISPLAY 0.787234 (-4475 3950);
PAINT MONO (-4475 3950);
DISPLAY INVISIBLE (-4475 3950);
FORCEPROP 1 LAST BODY_TYPE PLUMBING
J 2
(-4475 3900);
DISPLAY 1.234043 (-4475 3900);
PAINT GREEN (-4475 3900);
DISPLAY INVISIBLE (-4475 3900);
FORCEPROP 1 LAST HDL_TAP TRUE
J 2
(-4800 3825);
DISPLAY 1.234043 (-4800 3825);
PAINT GREEN (-4800 3825);
DISPLAY INVISIBLE (-4800 3825);
FORCEPROP 1 LAST PATH I128
J 2
(-4473 3950);
DISPLAY 0.872340 (-4473 3950);
PAINT GREEN (-4473 3950);
DISPLAY INVISIBLE (-4473 3950);
FORCEADD TAP..6
R 2
(-4475 4000);
FORCEPROP 3 LASTPIN (-4525 4000) SIG_NAME M_H_DQ<56>
J 0
(-4515 4010);
DISPLAY 0.659574 (-4515 4010);
PAINT MONO (-4515 4010);
DISPLAY INVISIBLE (-4515 4010);
FORCEPROP 1 LASTPIN (-4525 4000) BN 56
J 2
(-4475 4010);
DISPLAY 0.617021 (-4475 4010);
PAINT PINK (-4475 4010);
FORCEPROP 2 LAST CDS_LIB mstr_standard
J 2
(-4475 4000);
DISPLAY 0.787234 (-4475 4000);
PAINT MONO (-4475 4000);
DISPLAY INVISIBLE (-4475 4000);
FORCEPROP 1 LAST BODY_TYPE PLUMBING
J 2
(-4475 3950);
DISPLAY 1.234043 (-4475 3950);
PAINT GREEN (-4475 3950);
DISPLAY INVISIBLE (-4475 3950);
FORCEPROP 1 LAST HDL_TAP TRUE
J 2
(-4800 3875);
DISPLAY 1.234043 (-4800 3875);
PAINT GREEN (-4800 3875);
DISPLAY INVISIBLE (-4800 3875);
FORCEPROP 1 LAST PATH I129
J 2
(-4473 4000);
DISPLAY 0.872340 (-4473 4000);
PAINT GREEN (-4473 4000);
DISPLAY INVISIBLE (-4473 4000);
FORCEADD OFFPAGE..6
(-6625 2350);
FORCEPROP 2 LAST $XR0 58 
J 0
(-6874 2350);
DISPLAY 0.638298 (-6874 2350);
PAINT MONO (-6874 2350);
FORCEPROP 2 LAST $XR1 79 
J 0
(-6964 2350);
DISPLAY 0.638298 (-6964 2350);
PAINT MONO (-6964 2350);
FORCEPROP 2 LAST CDS_LIB mstr_standard
J 0
(-6625 2350);
DISPLAY 0.787234 (-6625 2350);
PAINT MONO (-6625 2350);
DISPLAY INVISIBLE (-6625 2350);
FORCEPROP 1 LAST OFFPAGE TRUE
J 0
(-6300 2225);
DISPLAY 0.936170 (-6300 2225);
PAINT GREEN (-6300 2225);
DISPLAY INVISIBLE (-6300 2225);
FORCEPROP 1 LAST COMMENT_BODY TRUE
J 0
(-6525 2275);
DISPLAY 0.936170 (-6525 2275);
PAINT GREEN (-6525 2275);
DISPLAY INVISIBLE (-6525 2275);
FORCEPROP 2 LAST PATH I13
J 0
(-6850 2400);
DISPLAY 1.021277 (-6850 2400);
PAINT ORANGE (-6850 2400);
DISPLAY INVISIBLE (-6850 2400);
FORCEADD TAP..6
R 2
(-4475 4150);
FORCEPROP 3 LASTPIN (-4525 4150) SIG_NAME M_H_DQ<59>
J 0
(-4515 4160);
DISPLAY 0.659574 (-4515 4160);
PAINT MONO (-4515 4160);
DISPLAY INVISIBLE (-4515 4160);
FORCEPROP 1 LASTPIN (-4525 4150) BN 59
J 2
(-4475 4160);
DISPLAY 0.617021 (-4475 4160);
PAINT PINK (-4475 4160);
FORCEPROP 2 LAST CDS_LIB mstr_standard
J 2
(-4475 4150);
DISPLAY 0.787234 (-4475 4150);
PAINT MONO (-4475 4150);
DISPLAY INVISIBLE (-4475 4150);
FORCEPROP 1 LAST BODY_TYPE PLUMBING
J 2
(-4475 4100);
DISPLAY 1.234043 (-4475 4100);
PAINT GREEN (-4475 4100);
DISPLAY INVISIBLE (-4475 4100);
FORCEPROP 1 LAST HDL_TAP TRUE
J 2
(-4800 4025);
DISPLAY 1.234043 (-4800 4025);
PAINT GREEN (-4800 4025);
DISPLAY INVISIBLE (-4800 4025);
FORCEPROP 1 LAST PATH I130
J 2
(-4473 4150);
DISPLAY 0.872340 (-4473 4150);
PAINT GREEN (-4473 4150);
DISPLAY INVISIBLE (-4473 4150);
FORCEADD TAP..6
R 2
(-4475 4100);
FORCEPROP 3 LASTPIN (-4525 4100) SIG_NAME M_H_DQ<58>
J 0
(-4515 4110);
DISPLAY 0.659574 (-4515 4110);
PAINT MONO (-4515 4110);
DISPLAY INVISIBLE (-4515 4110);
FORCEPROP 1 LASTPIN (-4525 4100) BN 58
J 2
(-4475 4110);
DISPLAY 0.617021 (-4475 4110);
PAINT PINK (-4475 4110);
FORCEPROP 2 LAST CDS_LIB mstr_standard
J 2
(-4475 4100);
DISPLAY 0.787234 (-4475 4100);
PAINT MONO (-4475 4100);
DISPLAY INVISIBLE (-4475 4100);
FORCEPROP 1 LAST BODY_TYPE PLUMBING
J 2
(-4475 4050);
DISPLAY 1.234043 (-4475 4050);
PAINT GREEN (-4475 4050);
DISPLAY INVISIBLE (-4475 4050);
FORCEPROP 1 LAST HDL_TAP TRUE
J 2
(-4800 3975);
DISPLAY 1.234043 (-4800 3975);
PAINT GREEN (-4800 3975);
DISPLAY INVISIBLE (-4800 3975);
FORCEPROP 1 LAST PATH I131
J 2
(-4473 4100);
DISPLAY 0.872340 (-4473 4100);
PAINT GREEN (-4473 4100);
DISPLAY INVISIBLE (-4473 4100);
FORCEADD TAP..6
R 2
(-4475 4300);
FORCEPROP 3 LASTPIN (-4525 4300) SIG_NAME M_H_DQ<62>
J 0
(-4515 4310);
DISPLAY 0.659574 (-4515 4310);
PAINT MONO (-4515 4310);
DISPLAY INVISIBLE (-4515 4310);
FORCEPROP 1 LASTPIN (-4525 4300) BN 62
J 2
(-4475 4310);
DISPLAY 0.617021 (-4475 4310);
PAINT PINK (-4475 4310);
FORCEPROP 2 LAST CDS_LIB mstr_standard
J 2
(-4475 4300);
DISPLAY 0.787234 (-4475 4300);
PAINT MONO (-4475 4300);
DISPLAY INVISIBLE (-4475 4300);
FORCEPROP 1 LAST BODY_TYPE PLUMBING
J 2
(-4475 4250);
DISPLAY 1.234043 (-4475 4250);
PAINT GREEN (-4475 4250);
DISPLAY INVISIBLE (-4475 4250);
FORCEPROP 1 LAST HDL_TAP TRUE
J 2
(-4800 4175);
DISPLAY 1.234043 (-4800 4175);
PAINT GREEN (-4800 4175);
DISPLAY INVISIBLE (-4800 4175);
FORCEPROP 1 LAST PATH I132
J 2
(-4473 4300);
DISPLAY 0.872340 (-4473 4300);
PAINT GREEN (-4473 4300);
DISPLAY INVISIBLE (-4473 4300);
FORCEADD TAP..6
R 2
(-4475 4200);
FORCEPROP 3 LASTPIN (-4525 4200) SIG_NAME M_H_DQ<60>
J 0
(-4515 4210);
DISPLAY 0.659574 (-4515 4210);
PAINT MONO (-4515 4210);
DISPLAY INVISIBLE (-4515 4210);
FORCEPROP 1 LASTPIN (-4525 4200) BN 60
J 2
(-4475 4210);
DISPLAY 0.617021 (-4475 4210);
PAINT PINK (-4475 4210);
FORCEPROP 2 LAST CDS_LIB mstr_standard
J 2
(-4475 4200);
DISPLAY 0.787234 (-4475 4200);
PAINT MONO (-4475 4200);
DISPLAY INVISIBLE (-4475 4200);
FORCEPROP 1 LAST BODY_TYPE PLUMBING
J 2
(-4475 4150);
DISPLAY 1.234043 (-4475 4150);
PAINT GREEN (-4475 4150);
DISPLAY INVISIBLE (-4475 4150);
FORCEPROP 1 LAST HDL_TAP TRUE
J 2
(-4800 4075);
DISPLAY 1.234043 (-4800 4075);
PAINT GREEN (-4800 4075);
DISPLAY INVISIBLE (-4800 4075);
FORCEPROP 1 LAST PATH I133
J 2
(-4473 4200);
DISPLAY 0.872340 (-4473 4200);
PAINT GREEN (-4473 4200);
DISPLAY INVISIBLE (-4473 4200);
FORCEADD TAP..6
R 2
(-4475 4250);
FORCEPROP 3 LASTPIN (-4525 4250) SIG_NAME M_H_DQ<61>
J 0
(-4515 4260);
DISPLAY 0.659574 (-4515 4260);
PAINT MONO (-4515 4260);
DISPLAY INVISIBLE (-4515 4260);
FORCEPROP 1 LASTPIN (-4525 4250) BN 61
J 2
(-4475 4260);
DISPLAY 0.617021 (-4475 4260);
PAINT PINK (-4475 4260);
FORCEPROP 2 LAST CDS_LIB mstr_standard
J 2
(-4475 4250);
DISPLAY 0.787234 (-4475 4250);
PAINT MONO (-4475 4250);
DISPLAY INVISIBLE (-4475 4250);
FORCEPROP 1 LAST BODY_TYPE PLUMBING
J 2
(-4475 4200);
DISPLAY 1.234043 (-4475 4200);
PAINT GREEN (-4475 4200);
DISPLAY INVISIBLE (-4475 4200);
FORCEPROP 1 LAST HDL_TAP TRUE
J 2
(-4800 4125);
DISPLAY 1.234043 (-4800 4125);
PAINT GREEN (-4800 4125);
DISPLAY INVISIBLE (-4800 4125);
FORCEPROP 1 LAST PATH I134
J 2
(-4473 4250);
DISPLAY 0.872340 (-4473 4250);
PAINT GREEN (-4473 4250);
DISPLAY INVISIBLE (-4473 4250);
FORCEADD TAP..6
R 2
(-4475 4350);
FORCEPROP 3 LASTPIN (-4525 4350) SIG_NAME M_H_DQ<63>
J 0
(-4515 4360);
DISPLAY 0.659574 (-4515 4360);
PAINT MONO (-4515 4360);
DISPLAY INVISIBLE (-4515 4360);
FORCEPROP 1 LASTPIN (-4525 4350) BN 63
J 2
(-4475 4360);
DISPLAY 0.617021 (-4475 4360);
PAINT PINK (-4475 4360);
FORCEPROP 2 LAST CDS_LIB mstr_standard
J 2
(-4475 4350);
DISPLAY 0.787234 (-4475 4350);
PAINT MONO (-4475 4350);
DISPLAY INVISIBLE (-4475 4350);
FORCEPROP 1 LAST BODY_TYPE PLUMBING
J 2
(-4475 4300);
DISPLAY 1.234043 (-4475 4300);
PAINT GREEN (-4475 4300);
DISPLAY INVISIBLE (-4475 4300);
FORCEPROP 1 LAST HDL_TAP TRUE
J 2
(-4800 4225);
DISPLAY 1.234043 (-4800 4225);
PAINT GREEN (-4800 4225);
DISPLAY INVISIBLE (-4800 4225);
FORCEPROP 1 LAST PATH I135
J 2
(-4473 4350);
DISPLAY 0.872340 (-4473 4350);
PAINT GREEN (-4473 4350);
DISPLAY INVISIBLE (-4473 4350);
FORCEADD OFFPAGE..3
(-3875 4400);
FORCEPROP 2 LAST $XR0 58 
J 0
(-3661 4400);
DISPLAY 0.638298 (-3661 4400);
PAINT MONO (-3661 4400);
FORCEPROP 2 LAST $XR1 79 
J 0
(-3571 4400);
DISPLAY 0.638298 (-3571 4400);
PAINT MONO (-3571 4400);
FORCEPROP 2 LAST CDS_LIB mstr_standard
J 0
(-3875 4400);
DISPLAY 0.787234 (-3875 4400);
PAINT MONO (-3875 4400);
DISPLAY INVISIBLE (-3875 4400);
FORCEPROP 1 LAST OFFPAGE TRUE
J 0
(-3550 4275);
DISPLAY 0.936170 (-3550 4275);
PAINT GREEN (-3550 4275);
DISPLAY INVISIBLE (-3550 4275);
FORCEPROP 1 LAST COMMENT_BODY TRUE
J 0
(-3925 4300);
DISPLAY 0.936170 (-3925 4300);
PAINT GREEN (-3925 4300);
DISPLAY INVISIBLE (-3925 4300);
FORCEPROP 2 LAST PATH I136
J 0
(-3650 4450);
DISPLAY 1.021277 (-3650 4450);
PAINT ORANGE (-3650 4450);
DISPLAY INVISIBLE (-3650 4450);
FORCEADD GND..1
R 2
(-1575 550);
FORCEPROP 3 LASTPIN (-1575 600) SIG_NAME GND\g
J 0
(-1565 610);
DISPLAY 0.659574 (-1565 610);
PAINT MONO (-1565 610);
DISPLAY INVISIBLE (-1565 610);
FORCEPROP 1 LAST VOLTAGE 0
J 0
(-1575 550);
PAINT SKYBLUE (-1575 550);
DISPLAY INVISIBLE (-1575 550);
FORCEPROP 2 LAST CDS_LIB mstr_symbols
J 0
(-1575 550);
DISPLAY 0.787234 (-1575 550);
PAINT MONO (-1575 550);
DISPLAY INVISIBLE (-1575 550);
FORCEPROP 1 LAST SIZE 1B
J 2
(-1650 500);
DISPLAY 1.170213 (-1650 500);
PAINT GREEN (-1650 500);
DISPLAY INVISIBLE (-1650 500);
FORCEPROP 2 LAST BOM_COST MEM
J 0
(-1575 555);
PAINT ORANGE (-1575 555);
DISPLAY INVISIBLE (-1575 555);
FORCEPROP 1 LAST BODY_TYPE PLUMBING
J 2
(-1530 507);
DISPLAY 0.340426 (-1530 507);
PAINT GREEN (-1530 507);
DISPLAY INVISIBLE (-1530 507);
FORCEPROP 1 LAST PATH I137
J 2
(-1650 550);
DISPLAY 0.872340 (-1650 550);
PAINT AQUA (-1650 550);
DISPLAY INVISIBLE (-1650 550);
FORCEPROP 2 LAST ROOM DDR4_GH_G
J 0
(-1575 555);
PAINT ORANGE (-1575 555);
DISPLAY INVISIBLE (-1575 555);
FORCEPROP 1 LAST HDL_POWER GND
J 2
(-1575 700);
DISPLAY 0.553191 (-1575 700);
PAINT GREEN (-1575 700);
DISPLAY INVISIBLE (-1575 700);
FORCEADD SCONN288_H44441003..3
(-875 1850);
FORCEPROP 1 LAST LOCATION J9U1
J 0
(-1325 3250);
DISPLAY 0.617021 (-1325 3250);
PAINT AQUA (-1325 3250);
FORCEPROP 1 LAST PART_NUMBER H44441-003
J 0
(-1325 500);
DISPLAY 0.617021 (-1325 500);
PAINT BLUE (-1325 500);
FORCEPROP 1 LAST MATERIAL SCONN
J 0
(-1325 3200);
DISPLAY 0.617021 (-1325 3200);
PAINT SKYBLUE (-1325 3200);
FORCEPROP 2 LASTPIN (-1375 3000) $PN 2
J 2
(-1385 3010);
DISPLAY 0.617021 (-1385 3010);
PAINT ORANGE (-1385 3010);
FORCEPROP 2 LASTPIN (-1375 2950) $PN 4
J 2
(-1385 2960);
DISPLAY 0.617021 (-1385 2960);
PAINT ORANGE (-1385 2960);
FORCEPROP 2 LASTPIN (-1375 2900) $PN 6
J 2
(-1385 2910);
DISPLAY 0.617021 (-1385 2910);
PAINT ORANGE (-1385 2910);
FORCEPROP 2 LASTPIN (-1375 2850) $PN 9
J 2
(-1385 2860);
DISPLAY 0.617021 (-1385 2860);
PAINT ORANGE (-1385 2860);
FORCEPROP 2 LASTPIN (-1375 2800) $PN 11
J 2
(-1385 2810);
DISPLAY 0.617021 (-1385 2810);
PAINT ORANGE (-1385 2810);
FORCEPROP 2 LASTPIN (-1375 2750) $PN 13
J 2
(-1385 2760);
DISPLAY 0.617021 (-1385 2760);
PAINT ORANGE (-1385 2760);
FORCEPROP 2 LASTPIN (-1375 2700) $PN 15
J 2
(-1385 2710);
DISPLAY 0.617021 (-1385 2710);
PAINT ORANGE (-1385 2710);
FORCEPROP 2 LASTPIN (-1375 2650) $PN 17
J 2
(-1385 2660);
DISPLAY 0.617021 (-1385 2660);
PAINT ORANGE (-1385 2660);
FORCEPROP 2 LASTPIN (-1375 2600) $PN 20
J 2
(-1385 2610);
DISPLAY 0.617021 (-1385 2610);
PAINT ORANGE (-1385 2610);
FORCEPROP 2 LASTPIN (-1375 2550) $PN 22
J 2
(-1385 2560);
DISPLAY 0.617021 (-1385 2560);
PAINT ORANGE (-1385 2560);
FORCEPROP 2 LASTPIN (-1375 2500) $PN 24
J 2
(-1385 2510);
DISPLAY 0.617021 (-1385 2510);
PAINT ORANGE (-1385 2510);
FORCEPROP 2 LASTPIN (-1375 2450) $PN 26
J 2
(-1385 2460);
DISPLAY 0.617021 (-1385 2460);
PAINT ORANGE (-1385 2460);
FORCEPROP 2 LASTPIN (-1375 2400) $PN 28
J 2
(-1385 2410);
DISPLAY 0.617021 (-1385 2410);
PAINT ORANGE (-1385 2410);
FORCEPROP 2 LASTPIN (-1375 2350) $PN 31
J 2
(-1385 2360);
DISPLAY 0.617021 (-1385 2360);
PAINT ORANGE (-1385 2360);
FORCEPROP 2 LASTPIN (-1375 2300) $PN 33
J 2
(-1385 2310);
DISPLAY 0.617021 (-1385 2310);
PAINT ORANGE (-1385 2310);
FORCEPROP 2 LASTPIN (-1375 2250) $PN 35
J 2
(-1385 2260);
DISPLAY 0.617021 (-1385 2260);
PAINT ORANGE (-1385 2260);
FORCEPROP 2 LASTPIN (-1375 2200) $PN 37
J 2
(-1385 2210);
DISPLAY 0.617021 (-1385 2210);
PAINT ORANGE (-1385 2210);
FORCEPROP 2 LASTPIN (-1375 2150) $PN 39
J 2
(-1385 2160);
DISPLAY 0.617021 (-1385 2160);
PAINT ORANGE (-1385 2160);
FORCEPROP 2 LASTPIN (-1375 2100) $PN 42
J 2
(-1385 2110);
DISPLAY 0.617021 (-1385 2110);
PAINT ORANGE (-1385 2110);
FORCEPROP 2 LASTPIN (-1375 2050) $PN 44
J 2
(-1385 2060);
DISPLAY 0.617021 (-1385 2060);
PAINT ORANGE (-1385 2060);
FORCEPROP 2 LASTPIN (-1375 2000) $PN 46
J 2
(-1385 2010);
DISPLAY 0.617021 (-1385 2010);
PAINT ORANGE (-1385 2010);
FORCEPROP 2 LASTPIN (-1375 1950) $PN 48
J 2
(-1385 1960);
DISPLAY 0.617021 (-1385 1960);
PAINT ORANGE (-1385 1960);
FORCEPROP 2 LASTPIN (-1375 1900) $PN 50
J 2
(-1385 1910);
DISPLAY 0.617021 (-1385 1910);
PAINT ORANGE (-1385 1910);
FORCEPROP 2 LASTPIN (-1375 1850) $PN 53
J 2
(-1385 1860);
DISPLAY 0.617021 (-1385 1860);
PAINT ORANGE (-1385 1860);
FORCEPROP 2 LASTPIN (-1375 1800) $PN 55
J 2
(-1385 1810);
DISPLAY 0.617021 (-1385 1810);
PAINT ORANGE (-1385 1810);
FORCEPROP 2 LASTPIN (-1375 1750) $PN 57
J 2
(-1385 1760);
DISPLAY 0.617021 (-1385 1760);
PAINT ORANGE (-1385 1760);
FORCEPROP 2 LASTPIN (-1375 1700) $PN 94
J 2
(-1385 1710);
DISPLAY 0.617021 (-1385 1710);
PAINT ORANGE (-1385 1710);
FORCEPROP 2 LASTPIN (-1375 1650) $PN 96
J 2
(-1385 1660);
DISPLAY 0.617021 (-1385 1660);
PAINT ORANGE (-1385 1660);
FORCEPROP 2 LASTPIN (-1375 1600) $PN 98
J 2
(-1385 1610);
DISPLAY 0.617021 (-1385 1610);
PAINT ORANGE (-1385 1610);
FORCEPROP 2 LASTPIN (-1375 1550) $PN 101
J 2
(-1385 1560);
DISPLAY 0.617021 (-1385 1560);
PAINT ORANGE (-1385 1560);
FORCEPROP 2 LASTPIN (-1375 1500) $PN 103
J 2
(-1385 1510);
DISPLAY 0.617021 (-1385 1510);
PAINT ORANGE (-1385 1510);
FORCEPROP 2 LASTPIN (-1375 1450) $PN 105
J 2
(-1385 1460);
DISPLAY 0.617021 (-1385 1460);
PAINT ORANGE (-1385 1460);
FORCEPROP 2 LASTPIN (-1375 1400) $PN 107
J 2
(-1385 1410);
DISPLAY 0.617021 (-1385 1410);
PAINT ORANGE (-1385 1410);
FORCEPROP 2 LASTPIN (-1375 1350) $PN 109
J 2
(-1385 1360);
DISPLAY 0.617021 (-1385 1360);
PAINT ORANGE (-1385 1360);
FORCEPROP 2 LASTPIN (-1375 1300) $PN 112
J 2
(-1385 1310);
DISPLAY 0.617021 (-1385 1310);
PAINT ORANGE (-1385 1310);
FORCEPROP 2 LASTPIN (-1375 1250) $PN 114
J 2
(-1385 1260);
DISPLAY 0.617021 (-1385 1260);
PAINT ORANGE (-1385 1260);
FORCEPROP 2 LASTPIN (-1375 1200) $PN 116
J 2
(-1385 1210);
DISPLAY 0.617021 (-1385 1210);
PAINT ORANGE (-1385 1210);
FORCEPROP 2 LASTPIN (-1375 1150) $PN 118
J 2
(-1385 1160);
DISPLAY 0.617021 (-1385 1160);
PAINT ORANGE (-1385 1160);
FORCEPROP 2 LASTPIN (-1375 1100) $PN 120
J 2
(-1385 1110);
DISPLAY 0.617021 (-1385 1110);
PAINT ORANGE (-1385 1110);
FORCEPROP 2 LASTPIN (-1375 1050) $PN 123
J 2
(-1385 1060);
DISPLAY 0.617021 (-1385 1060);
PAINT ORANGE (-1385 1060);
FORCEPROP 2 LASTPIN (-1375 1000) $PN 125
J 2
(-1385 1010);
DISPLAY 0.617021 (-1385 1010);
PAINT ORANGE (-1385 1010);
FORCEPROP 2 LASTPIN (-1375 950) $PN 127
J 2
(-1385 960);
DISPLAY 0.617021 (-1385 960);
PAINT ORANGE (-1385 960);
FORCEPROP 2 LASTPIN (-1375 900) $PN 129
J 2
(-1385 910);
DISPLAY 0.617021 (-1385 910);
PAINT ORANGE (-1385 910);
FORCEPROP 2 LASTPIN (-1375 850) $PN 131
J 2
(-1385 860);
DISPLAY 0.617021 (-1385 860);
PAINT ORANGE (-1385 860);
FORCEPROP 2 LASTPIN (-1375 800) $PN 134
J 2
(-1385 810);
DISPLAY 0.617021 (-1385 810);
PAINT ORANGE (-1385 810);
FORCEPROP 2 LASTPIN (-1375 750) $PN 136
J 2
(-1385 760);
DISPLAY 0.617021 (-1385 760);
PAINT ORANGE (-1385 760);
FORCEPROP 2 LASTPIN (-1375 700) $PN 138
J 2
(-1385 710);
DISPLAY 0.617021 (-1385 710);
PAINT ORANGE (-1385 710);
FORCEPROP 2 LASTPIN (-375 3000) $PN 147
J 0
(-365 3010);
DISPLAY 0.617021 (-365 3010);
PAINT ORANGE (-365 3010);
FORCEPROP 2 LASTPIN (-375 2950) $PN 149
J 0
(-365 2960);
DISPLAY 0.617021 (-365 2960);
PAINT ORANGE (-365 2960);
FORCEPROP 2 LASTPIN (-375 2900) $PN 151
J 0
(-365 2910);
DISPLAY 0.617021 (-365 2910);
PAINT ORANGE (-365 2910);
FORCEPROP 2 LASTPIN (-375 2850) $PN 154
J 0
(-365 2860);
DISPLAY 0.617021 (-365 2860);
PAINT ORANGE (-365 2860);
FORCEPROP 2 LASTPIN (-375 2800) $PN 156
J 0
(-365 2810);
DISPLAY 0.617021 (-365 2810);
PAINT ORANGE (-365 2810);
FORCEPROP 2 LASTPIN (-375 2750) $PN 158
J 0
(-365 2760);
DISPLAY 0.617021 (-365 2760);
PAINT ORANGE (-365 2760);
FORCEPROP 2 LASTPIN (-375 2700) $PN 160
J 0
(-365 2710);
DISPLAY 0.617021 (-365 2710);
PAINT ORANGE (-365 2710);
FORCEPROP 2 LASTPIN (-375 2650) $PN 162
J 0
(-365 2660);
DISPLAY 0.617021 (-365 2660);
PAINT ORANGE (-365 2660);
FORCEPROP 2 LASTPIN (-375 2600) $PN 165
J 0
(-365 2610);
DISPLAY 0.617021 (-365 2610);
PAINT ORANGE (-365 2610);
FORCEPROP 2 LASTPIN (-375 2550) $PN 167
J 0
(-365 2560);
DISPLAY 0.617021 (-365 2560);
PAINT ORANGE (-365 2560);
FORCEPROP 2 LASTPIN (-375 2500) $PN 169
J 0
(-365 2510);
DISPLAY 0.617021 (-365 2510);
PAINT ORANGE (-365 2510);
FORCEPROP 2 LASTPIN (-375 2450) $PN 171
J 0
(-365 2460);
DISPLAY 0.617021 (-365 2460);
PAINT ORANGE (-365 2460);
FORCEPROP 2 LASTPIN (-375 2400) $PN 173
J 0
(-365 2410);
DISPLAY 0.617021 (-365 2410);
PAINT ORANGE (-365 2410);
FORCEPROP 2 LASTPIN (-375 2350) $PN 176
J 0
(-365 2360);
DISPLAY 0.617021 (-365 2360);
PAINT ORANGE (-365 2360);
FORCEPROP 2 LASTPIN (-375 2300) $PN 178
J 0
(-365 2310);
DISPLAY 0.617021 (-365 2310);
PAINT ORANGE (-365 2310);
FORCEPROP 2 LASTPIN (-375 2250) $PN 180
J 0
(-365 2260);
DISPLAY 0.617021 (-365 2260);
PAINT ORANGE (-365 2260);
FORCEPROP 2 LASTPIN (-375 2200) $PN 182
J 0
(-365 2210);
DISPLAY 0.617021 (-365 2210);
PAINT ORANGE (-365 2210);
FORCEPROP 2 LASTPIN (-375 2150) $PN 184
J 0
(-365 2160);
DISPLAY 0.617021 (-365 2160);
PAINT ORANGE (-365 2160);
FORCEPROP 2 LASTPIN (-375 2100) $PN 187
J 0
(-365 2110);
DISPLAY 0.617021 (-365 2110);
PAINT ORANGE (-365 2110);
FORCEPROP 2 LASTPIN (-375 2050) $PN 189
J 0
(-365 2060);
DISPLAY 0.617021 (-365 2060);
PAINT ORANGE (-365 2060);
FORCEPROP 2 LASTPIN (-375 2000) $PN 191
J 0
(-365 2010);
DISPLAY 0.617021 (-365 2010);
PAINT ORANGE (-365 2010);
FORCEPROP 2 LASTPIN (-375 1950) $PN 193
J 0
(-365 1960);
DISPLAY 0.617021 (-365 1960);
PAINT ORANGE (-365 1960);
FORCEPROP 2 LASTPIN (-375 1900) $PN 195
J 0
(-365 1910);
DISPLAY 0.617021 (-365 1910);
PAINT ORANGE (-365 1910);
FORCEPROP 2 LASTPIN (-375 1850) $PN 198
J 0
(-365 1860);
DISPLAY 0.617021 (-365 1860);
PAINT ORANGE (-365 1860);
FORCEPROP 2 LASTPIN (-375 1800) $PN 200
J 0
(-365 1810);
DISPLAY 0.617021 (-365 1810);
PAINT ORANGE (-365 1810);
FORCEPROP 2 LASTPIN (-375 1750) $PN 202
J 0
(-365 1760);
DISPLAY 0.617021 (-365 1760);
PAINT ORANGE (-365 1760);
FORCEPROP 2 LASTPIN (-375 1700) $PN 239
J 0
(-365 1710);
DISPLAY 0.617021 (-365 1710);
PAINT ORANGE (-365 1710);
FORCEPROP 2 LASTPIN (-375 1650) $PN 241
J 0
(-365 1660);
DISPLAY 0.617021 (-365 1660);
PAINT ORANGE (-365 1660);
FORCEPROP 2 LASTPIN (-375 1600) $PN 243
J 0
(-365 1610);
DISPLAY 0.617021 (-365 1610);
PAINT ORANGE (-365 1610);
FORCEPROP 2 LASTPIN (-375 1550) $PN 246
J 0
(-365 1560);
DISPLAY 0.617021 (-365 1560);
PAINT ORANGE (-365 1560);
FORCEPROP 2 LASTPIN (-375 1500) $PN 248
J 0
(-365 1510);
DISPLAY 0.617021 (-365 1510);
PAINT ORANGE (-365 1510);
FORCEPROP 2 LASTPIN (-375 1450) $PN 250
J 0
(-365 1460);
DISPLAY 0.617021 (-365 1460);
PAINT ORANGE (-365 1460);
FORCEPROP 2 LASTPIN (-375 1400) $PN 252
J 0
(-365 1410);
DISPLAY 0.617021 (-365 1410);
PAINT ORANGE (-365 1410);
FORCEPROP 2 LASTPIN (-375 1350) $PN 254
J 0
(-365 1360);
DISPLAY 0.617021 (-365 1360);
PAINT ORANGE (-365 1360);
FORCEPROP 2 LASTPIN (-375 1300) $PN 257
J 0
(-365 1310);
DISPLAY 0.617021 (-365 1310);
PAINT ORANGE (-365 1310);
FORCEPROP 2 LASTPIN (-375 1250) $PN 259
J 0
(-365 1260);
DISPLAY 0.617021 (-365 1260);
PAINT ORANGE (-365 1260);
FORCEPROP 2 LASTPIN (-375 1200) $PN 261
J 0
(-365 1210);
DISPLAY 0.617021 (-365 1210);
PAINT ORANGE (-365 1210);
FORCEPROP 2 LASTPIN (-375 1150) $PN 263
J 0
(-365 1160);
DISPLAY 0.617021 (-365 1160);
PAINT ORANGE (-365 1160);
FORCEPROP 2 LASTPIN (-375 1100) $PN 265
J 0
(-365 1110);
DISPLAY 0.617021 (-365 1110);
PAINT ORANGE (-365 1110);
FORCEPROP 2 LASTPIN (-375 1050) $PN 268
J 0
(-365 1060);
DISPLAY 0.617021 (-365 1060);
PAINT ORANGE (-365 1060);
FORCEPROP 2 LASTPIN (-375 1000) $PN 270
J 0
(-365 1010);
DISPLAY 0.617021 (-365 1010);
PAINT ORANGE (-365 1010);
FORCEPROP 2 LASTPIN (-375 950) $PN 272
J 0
(-365 960);
DISPLAY 0.617021 (-365 960);
PAINT ORANGE (-365 960);
FORCEPROP 2 LASTPIN (-375 900) $PN 274
J 0
(-365 910);
DISPLAY 0.617021 (-365 910);
PAINT ORANGE (-365 910);
FORCEPROP 2 LASTPIN (-375 850) $PN 276
J 0
(-365 860);
DISPLAY 0.617021 (-365 860);
PAINT ORANGE (-365 860);
FORCEPROP 2 LASTPIN (-375 800) $PN 279
J 0
(-365 810);
DISPLAY 0.617021 (-365 810);
PAINT ORANGE (-365 810);
FORCEPROP 2 LASTPIN (-375 750) $PN 281
J 0
(-365 760);
DISPLAY 0.617021 (-365 760);
PAINT ORANGE (-365 760);
FORCEPROP 2 LASTPIN (-375 700) $PN 283
J 0
(-365 710);
DISPLAY 0.617021 (-365 710);
PAINT ORANGE (-365 710);
FORCEPROP 1 LAST PACK_TYPE PIP
J 0
(-1325 3300);
PAINT SKYBLUE (-1325 3300);
DISPLAY INVISIBLE (-1325 3300);
FORCEPROP 2 LAST BOM_COST MEM
J 0
(-875 1850);
PAINT ORANGE (-875 1850);
DISPLAY INVISIBLE (-875 1850);
FORCEPROP 2 LAST CDS_LIB mstr_sconn
J 0
(-875 1850);
PAINT ORANGE (-875 1850);
DISPLAY INVISIBLE (-875 1850);
FORCEPROP 2 LAST SEC_TYPE PIP
J 0
(-1325 3300);
DISPLAY 1.021277 (-1325 3300);
PAINT ORANGE (-1325 3300);
DISPLAY INVISIBLE (-1325 3300);
FORCEPROP 2 LAST SEC 3
J 0
(-1325 3300);
DISPLAY 0.680851 (-1325 3300);
PAINT MONO (-1325 3300);
DISPLAY INVISIBLE (-1325 3300);
FORCEPROP 2 LAST CDS_LOCATION J9U1
J 0
(-1325 3250);
DISPLAY 0.617021 (-1325 3250);
PAINT AQUA (-1325 3250);
DISPLAY INVISIBLE (-1325 3250);
FORCEPROP 1 LAST PATH I138
J 0
(-875 3200);
PAINT GREEN (-875 3200);
DISPLAY INVISIBLE (-875 3200);
FORCEPROP 2 LAST ROOM DDR4_GH_H
J 0
(-875 1850);
PAINT ORANGE (-875 1850);
DISPLAY INVISIBLE (-875 1850);
FORCEADD OFFPAGE..1
(-6625 2300);
FORCEPROP 2 LAST $XR0 58 
J 0
(-6876 2300);
DISPLAY 0.638298 (-6876 2300);
PAINT MONO (-6876 2300);
FORCEPROP 2 LAST $XR1 79 
J 0
(-6966 2300);
DISPLAY 0.638298 (-6966 2300);
PAINT MONO (-6966 2300);
FORCEPROP 2 LAST CDS_LIB mstr_standard
J 0
(-6625 2300);
DISPLAY 0.787234 (-6625 2300);
PAINT MONO (-6625 2300);
DISPLAY INVISIBLE (-6625 2300);
FORCEPROP 1 LAST OFFPAGE TRUE
J 0
(-6300 2175);
DISPLAY 0.936170 (-6300 2175);
PAINT GREEN (-6300 2175);
DISPLAY INVISIBLE (-6300 2175);
FORCEPROP 1 LAST COMMENT_BODY TRUE
J 0
(-6500 2200);
DISPLAY 0.936170 (-6500 2200);
PAINT GREEN (-6500 2200);
DISPLAY INVISIBLE (-6500 2200);
FORCEPROP 2 LAST PATH I14
J 0
(-6875 2350);
DISPLAY 1.021277 (-6875 2350);
PAINT ORANGE (-6875 2350);
DISPLAY INVISIBLE (-6875 2350);
FORCEADD TAP..6
R 2
(-1975 3000);
FORCEPROP 3 LASTPIN (-2025 3000) SIG_NAME M_H_DQS_DP<1>
J 0
(-2015 3010);
DISPLAY 0.659574 (-2015 3010);
PAINT MONO (-2015 3010);
DISPLAY INVISIBLE (-2015 3010);
FORCEPROP 1 LASTPIN (-2025 3000) BN 1
J 2
(-1975 3010);
DISPLAY 0.617021 (-1975 3010);
PAINT PINK (-1975 3010);
FORCEPROP 2 LAST CDS_LIB mstr_standard
J 0
(-1975 3000);
DISPLAY 0.787234 (-1975 3000);
PAINT MONO (-1975 3000);
DISPLAY INVISIBLE (-1975 3000);
FORCEPROP 1 LAST BODY_TYPE PLUMBING
J 2
(-1975 2950);
DISPLAY 1.234043 (-1975 2950);
PAINT GREEN (-1975 2950);
DISPLAY INVISIBLE (-1975 2950);
FORCEPROP 1 LAST HDL_TAP TRUE
J 2
(-2300 2875);
DISPLAY 1.234043 (-2300 2875);
PAINT GREEN (-2300 2875);
DISPLAY INVISIBLE (-2300 2875);
FORCEPROP 1 LAST PATH I142
J 2
(-1973 3000);
DISPLAY 0.872340 (-1973 3000);
PAINT GREEN (-1973 3000);
DISPLAY INVISIBLE (-1973 3000);
FORCEADD TAP..6
R 2
(-1975 2900);
FORCEPROP 3 LASTPIN (-2025 2900) SIG_NAME M_H_DQS_DP<0>
J 0
(-2015 2910);
DISPLAY 0.659574 (-2015 2910);
PAINT MONO (-2015 2910);
DISPLAY INVISIBLE (-2015 2910);
FORCEPROP 1 LASTPIN (-2025 2900) BN 0
J 2
(-1975 2910);
DISPLAY 0.617021 (-1975 2910);
PAINT PINK (-1975 2910);
FORCEPROP 2 LAST CDS_LIB mstr_standard
J 0
(-1975 2900);
DISPLAY 0.787234 (-1975 2900);
PAINT MONO (-1975 2900);
DISPLAY INVISIBLE (-1975 2900);
FORCEPROP 1 LAST BODY_TYPE PLUMBING
J 2
(-1975 2850);
DISPLAY 1.234043 (-1975 2850);
PAINT GREEN (-1975 2850);
DISPLAY INVISIBLE (-1975 2850);
FORCEPROP 1 LAST HDL_TAP TRUE
J 2
(-2300 2775);
DISPLAY 1.234043 (-2300 2775);
PAINT GREEN (-2300 2775);
DISPLAY INVISIBLE (-2300 2775);
FORCEPROP 1 LAST PATH I143
J 2
(-1973 2900);
DISPLAY 0.872340 (-1973 2900);
PAINT GREEN (-1973 2900);
DISPLAY INVISIBLE (-1973 2900);
FORCEADD TAP..6
R 2
(-1775 2850);
FORCEPROP 3 LASTPIN (-1825 2850) SIG_NAME M_H_DQS_DN<0>
J 0
(-1815 2860);
DISPLAY 0.659574 (-1815 2860);
PAINT MONO (-1815 2860);
DISPLAY INVISIBLE (-1815 2860);
FORCEPROP 1 LASTPIN (-1825 2850) BN 0
J 2
(-1775 2860);
DISPLAY 0.617021 (-1775 2860);
PAINT PINK (-1775 2860);
FORCEPROP 2 LAST CDS_LIB mstr_standard
J 0
(-1775 2850);
DISPLAY 0.787234 (-1775 2850);
PAINT MONO (-1775 2850);
DISPLAY INVISIBLE (-1775 2850);
FORCEPROP 1 LAST BODY_TYPE PLUMBING
J 2
(-1775 2800);
DISPLAY 1.234043 (-1775 2800);
PAINT GREEN (-1775 2800);
DISPLAY INVISIBLE (-1775 2800);
FORCEPROP 1 LAST HDL_TAP TRUE
J 2
(-2100 2725);
DISPLAY 1.234043 (-2100 2725);
PAINT GREEN (-2100 2725);
DISPLAY INVISIBLE (-2100 2725);
FORCEPROP 1 LAST PATH I144
J 2
(-1773 2850);
DISPLAY 0.872340 (-1773 2850);
PAINT GREEN (-1773 2850);
DISPLAY INVISIBLE (-1773 2850);
FORCEADD TAP..6
R 2
(-1775 2950);
FORCEPROP 3 LASTPIN (-1825 2950) SIG_NAME M_H_DQS_DN<1>
J 0
(-1815 2960);
DISPLAY 0.659574 (-1815 2960);
PAINT MONO (-1815 2960);
DISPLAY INVISIBLE (-1815 2960);
FORCEPROP 1 LASTPIN (-1825 2950) BN 1
J 2
(-1775 2960);
DISPLAY 0.617021 (-1775 2960);
PAINT PINK (-1775 2960);
FORCEPROP 2 LAST CDS_LIB mstr_standard
J 0
(-1775 2950);
DISPLAY 0.787234 (-1775 2950);
PAINT MONO (-1775 2950);
DISPLAY INVISIBLE (-1775 2950);
FORCEPROP 1 LAST BODY_TYPE PLUMBING
J 2
(-1775 2900);
DISPLAY 1.234043 (-1775 2900);
PAINT GREEN (-1775 2900);
DISPLAY INVISIBLE (-1775 2900);
FORCEPROP 1 LAST HDL_TAP TRUE
J 2
(-2100 2825);
DISPLAY 1.234043 (-2100 2825);
PAINT GREEN (-2100 2825);
DISPLAY INVISIBLE (-2100 2825);
FORCEPROP 1 LAST PATH I145
J 2
(-1773 2950);
DISPLAY 0.872340 (-1773 2950);
PAINT GREEN (-1773 2950);
DISPLAY INVISIBLE (-1773 2950);
FORCEADD TAP..6
R 2
(-1975 3100);
FORCEPROP 3 LASTPIN (-2025 3100) SIG_NAME M_H_DQS_DP<2>
J 0
(-2015 3110);
DISPLAY 0.659574 (-2015 3110);
PAINT MONO (-2015 3110);
DISPLAY INVISIBLE (-2015 3110);
FORCEPROP 1 LASTPIN (-2025 3100) BN 2
J 2
(-1975 3110);
DISPLAY 0.617021 (-1975 3110);
PAINT PINK (-1975 3110);
FORCEPROP 2 LAST CDS_LIB mstr_standard
J 0
(-1975 3100);
DISPLAY 0.787234 (-1975 3100);
PAINT MONO (-1975 3100);
DISPLAY INVISIBLE (-1975 3100);
FORCEPROP 1 LAST BODY_TYPE PLUMBING
J 2
(-1975 3050);
DISPLAY 1.234043 (-1975 3050);
PAINT GREEN (-1975 3050);
DISPLAY INVISIBLE (-1975 3050);
FORCEPROP 1 LAST HDL_TAP TRUE
J 2
(-2300 2975);
DISPLAY 1.234043 (-2300 2975);
PAINT GREEN (-2300 2975);
DISPLAY INVISIBLE (-2300 2975);
FORCEPROP 1 LAST PATH I146
J 2
(-1973 3100);
DISPLAY 0.872340 (-1973 3100);
PAINT GREEN (-1973 3100);
DISPLAY INVISIBLE (-1973 3100);
FORCEADD TAP..6
R 2
(-1975 3200);
FORCEPROP 3 LASTPIN (-2025 3200) SIG_NAME M_H_DQS_DP<3>
J 0
(-2015 3210);
DISPLAY 0.659574 (-2015 3210);
PAINT MONO (-2015 3210);
DISPLAY INVISIBLE (-2015 3210);
FORCEPROP 1 LASTPIN (-2025 3200) BN 3
J 2
(-1975 3210);
DISPLAY 0.617021 (-1975 3210);
PAINT PINK (-1975 3210);
FORCEPROP 2 LAST CDS_LIB mstr_standard
J 0
(-1975 3200);
DISPLAY 0.787234 (-1975 3200);
PAINT MONO (-1975 3200);
DISPLAY INVISIBLE (-1975 3200);
FORCEPROP 1 LAST BODY_TYPE PLUMBING
J 2
(-1975 3150);
DISPLAY 1.234043 (-1975 3150);
PAINT GREEN (-1975 3150);
DISPLAY INVISIBLE (-1975 3150);
FORCEPROP 1 LAST HDL_TAP TRUE
J 2
(-2300 3075);
DISPLAY 1.234043 (-2300 3075);
PAINT GREEN (-2300 3075);
DISPLAY INVISIBLE (-2300 3075);
FORCEPROP 1 LAST PATH I147
J 2
(-1973 3200);
DISPLAY 0.872340 (-1973 3200);
PAINT GREEN (-1973 3200);
DISPLAY INVISIBLE (-1973 3200);
FORCEADD TAP..6
R 2
(-1975 3500);
FORCEPROP 3 LASTPIN (-2025 3500) SIG_NAME M_H_DQS_DP<6>
J 0
(-2015 3510);
DISPLAY 0.659574 (-2015 3510);
PAINT MONO (-2015 3510);
DISPLAY INVISIBLE (-2015 3510);
FORCEPROP 1 LASTPIN (-2025 3500) BN 6
J 2
(-1975 3510);
DISPLAY 0.617021 (-1975 3510);
PAINT PINK (-1975 3510);
FORCEPROP 2 LAST CDS_LIB mstr_standard
J 0
(-1975 3500);
DISPLAY 0.787234 (-1975 3500);
PAINT MONO (-1975 3500);
DISPLAY INVISIBLE (-1975 3500);
FORCEPROP 1 LAST BODY_TYPE PLUMBING
J 2
(-1975 3450);
DISPLAY 1.234043 (-1975 3450);
PAINT GREEN (-1975 3450);
DISPLAY INVISIBLE (-1975 3450);
FORCEPROP 1 LAST HDL_TAP TRUE
J 2
(-2300 3375);
DISPLAY 1.234043 (-2300 3375);
PAINT GREEN (-2300 3375);
DISPLAY INVISIBLE (-2300 3375);
FORCEPROP 1 LAST PATH I148
J 2
(-1973 3500);
DISPLAY 0.872340 (-1973 3500);
PAINT GREEN (-1973 3500);
DISPLAY INVISIBLE (-1973 3500);
FORCEADD TAP..6
R 2
(-1975 3400);
FORCEPROP 3 LASTPIN (-2025 3400) SIG_NAME M_H_DQS_DP<5>
J 0
(-2015 3410);
DISPLAY 0.659574 (-2015 3410);
PAINT MONO (-2015 3410);
DISPLAY INVISIBLE (-2015 3410);
FORCEPROP 1 LASTPIN (-2025 3400) BN 5
J 2
(-1975 3410);
DISPLAY 0.617021 (-1975 3410);
PAINT PINK (-1975 3410);
FORCEPROP 2 LAST CDS_LIB mstr_standard
J 0
(-1975 3400);
DISPLAY 0.787234 (-1975 3400);
PAINT MONO (-1975 3400);
DISPLAY INVISIBLE (-1975 3400);
FORCEPROP 1 LAST BODY_TYPE PLUMBING
J 2
(-1975 3350);
DISPLAY 1.234043 (-1975 3350);
PAINT GREEN (-1975 3350);
DISPLAY INVISIBLE (-1975 3350);
FORCEPROP 1 LAST HDL_TAP TRUE
J 2
(-2300 3275);
DISPLAY 1.234043 (-2300 3275);
PAINT GREEN (-2300 3275);
DISPLAY INVISIBLE (-2300 3275);
FORCEPROP 1 LAST PATH I149
J 2
(-1973 3400);
DISPLAY 0.872340 (-1973 3400);
PAINT GREEN (-1973 3400);
DISPLAY INVISIBLE (-1973 3400);
FORCEADD OFFPAGE..1
(-6625 2500);
FORCEPROP 2 LAST $XR0 58 
J 0
(-6846 2500);
DISPLAY 0.638298 (-6846 2500);
PAINT MONO (-6846 2500);
FORCEPROP 2 LAST $XR1 79 
J 0
(-6936 2500);
DISPLAY 0.638298 (-6936 2500);
PAINT MONO (-6936 2500);
FORCEPROP 2 LAST CDS_LIB mstr_standard
J 0
(-6625 2500);
DISPLAY 0.787234 (-6625 2500);
PAINT MONO (-6625 2500);
DISPLAY INVISIBLE (-6625 2500);
FORCEPROP 1 LAST OFFPAGE TRUE
J 0
(-6300 2375);
DISPLAY 0.936170 (-6300 2375);
PAINT GREEN (-6300 2375);
DISPLAY INVISIBLE (-6300 2375);
FORCEPROP 1 LAST COMMENT_BODY TRUE
J 0
(-6500 2400);
DISPLAY 0.936170 (-6500 2400);
PAINT GREEN (-6500 2400);
DISPLAY INVISIBLE (-6500 2400);
FORCEPROP 2 LAST PATH I15
J 0
(-6875 2550);
DISPLAY 1.021277 (-6875 2550);
PAINT ORANGE (-6875 2550);
DISPLAY INVISIBLE (-6875 2550);
FORCEADD TAP..6
R 2
(-1975 3300);
FORCEPROP 3 LASTPIN (-2025 3300) SIG_NAME M_H_DQS_DP<4>
J 0
(-2015 3310);
DISPLAY 0.659574 (-2015 3310);
PAINT MONO (-2015 3310);
DISPLAY INVISIBLE (-2015 3310);
FORCEPROP 1 LASTPIN (-2025 3300) BN 4
J 2
(-1975 3310);
DISPLAY 0.617021 (-1975 3310);
PAINT PINK (-1975 3310);
FORCEPROP 2 LAST CDS_LIB mstr_standard
J 0
(-1975 3300);
DISPLAY 0.787234 (-1975 3300);
PAINT MONO (-1975 3300);
DISPLAY INVISIBLE (-1975 3300);
FORCEPROP 1 LAST BODY_TYPE PLUMBING
J 2
(-1975 3250);
DISPLAY 1.234043 (-1975 3250);
PAINT GREEN (-1975 3250);
DISPLAY INVISIBLE (-1975 3250);
FORCEPROP 1 LAST HDL_TAP TRUE
J 2
(-2300 3175);
DISPLAY 1.234043 (-2300 3175);
PAINT GREEN (-2300 3175);
DISPLAY INVISIBLE (-2300 3175);
FORCEPROP 1 LAST PATH I150
J 2
(-1973 3300);
DISPLAY 0.872340 (-1973 3300);
PAINT GREEN (-1973 3300);
DISPLAY INVISIBLE (-1973 3300);
FORCEADD TAP..6
R 2
(-1775 3150);
FORCEPROP 3 LASTPIN (-1825 3150) SIG_NAME M_H_DQS_DN<3>
J 0
(-1815 3160);
DISPLAY 0.659574 (-1815 3160);
PAINT MONO (-1815 3160);
DISPLAY INVISIBLE (-1815 3160);
FORCEPROP 1 LASTPIN (-1825 3150) BN 3
J 2
(-1775 3160);
DISPLAY 0.617021 (-1775 3160);
PAINT PINK (-1775 3160);
FORCEPROP 2 LAST CDS_LIB mstr_standard
J 0
(-1775 3150);
DISPLAY 0.787234 (-1775 3150);
PAINT MONO (-1775 3150);
DISPLAY INVISIBLE (-1775 3150);
FORCEPROP 1 LAST BODY_TYPE PLUMBING
J 2
(-1775 3100);
DISPLAY 1.234043 (-1775 3100);
PAINT GREEN (-1775 3100);
DISPLAY INVISIBLE (-1775 3100);
FORCEPROP 1 LAST HDL_TAP TRUE
J 2
(-2100 3025);
DISPLAY 1.234043 (-2100 3025);
PAINT GREEN (-2100 3025);
DISPLAY INVISIBLE (-2100 3025);
FORCEPROP 1 LAST PATH I151
J 2
(-1773 3150);
DISPLAY 0.872340 (-1773 3150);
PAINT GREEN (-1773 3150);
DISPLAY INVISIBLE (-1773 3150);
FORCEADD TAP..6
R 2
(-1775 3050);
FORCEPROP 3 LASTPIN (-1825 3050) SIG_NAME M_H_DQS_DN<2>
J 0
(-1815 3060);
DISPLAY 0.659574 (-1815 3060);
PAINT MONO (-1815 3060);
DISPLAY INVISIBLE (-1815 3060);
FORCEPROP 1 LASTPIN (-1825 3050) BN 2
J 2
(-1775 3060);
DISPLAY 0.617021 (-1775 3060);
PAINT PINK (-1775 3060);
FORCEPROP 2 LAST CDS_LIB mstr_standard
J 0
(-1775 3050);
DISPLAY 0.787234 (-1775 3050);
PAINT MONO (-1775 3050);
DISPLAY INVISIBLE (-1775 3050);
FORCEPROP 1 LAST BODY_TYPE PLUMBING
J 2
(-1775 3000);
DISPLAY 1.234043 (-1775 3000);
PAINT GREEN (-1775 3000);
DISPLAY INVISIBLE (-1775 3000);
FORCEPROP 1 LAST HDL_TAP TRUE
J 2
(-2100 2925);
DISPLAY 1.234043 (-2100 2925);
PAINT GREEN (-2100 2925);
DISPLAY INVISIBLE (-2100 2925);
FORCEPROP 1 LAST PATH I152
J 2
(-1773 3050);
DISPLAY 0.872340 (-1773 3050);
PAINT GREEN (-1773 3050);
DISPLAY INVISIBLE (-1773 3050);
FORCEADD TAP..6
R 2
(-1775 3250);
FORCEPROP 3 LASTPIN (-1825 3250) SIG_NAME M_H_DQS_DN<4>
J 0
(-1815 3260);
DISPLAY 0.659574 (-1815 3260);
PAINT MONO (-1815 3260);
DISPLAY INVISIBLE (-1815 3260);
FORCEPROP 1 LASTPIN (-1825 3250) BN 4
J 2
(-1775 3260);
DISPLAY 0.617021 (-1775 3260);
PAINT PINK (-1775 3260);
FORCEPROP 2 LAST CDS_LIB mstr_standard
J 0
(-1775 3250);
DISPLAY 0.787234 (-1775 3250);
PAINT MONO (-1775 3250);
DISPLAY INVISIBLE (-1775 3250);
FORCEPROP 1 LAST BODY_TYPE PLUMBING
J 2
(-1775 3200);
DISPLAY 1.234043 (-1775 3200);
PAINT GREEN (-1775 3200);
DISPLAY INVISIBLE (-1775 3200);
FORCEPROP 1 LAST HDL_TAP TRUE
J 2
(-2100 3125);
DISPLAY 1.234043 (-2100 3125);
PAINT GREEN (-2100 3125);
DISPLAY INVISIBLE (-2100 3125);
FORCEPROP 1 LAST PATH I153
J 2
(-1773 3250);
DISPLAY 0.872340 (-1773 3250);
PAINT GREEN (-1773 3250);
DISPLAY INVISIBLE (-1773 3250);
FORCEADD TAP..6
R 2
(-1775 3350);
FORCEPROP 3 LASTPIN (-1825 3350) SIG_NAME M_H_DQS_DN<5>
J 0
(-1815 3360);
DISPLAY 0.659574 (-1815 3360);
PAINT MONO (-1815 3360);
DISPLAY INVISIBLE (-1815 3360);
FORCEPROP 1 LASTPIN (-1825 3350) BN 5
J 2
(-1775 3360);
DISPLAY 0.617021 (-1775 3360);
PAINT PINK (-1775 3360);
FORCEPROP 2 LAST CDS_LIB mstr_standard
J 0
(-1775 3350);
DISPLAY 0.787234 (-1775 3350);
PAINT MONO (-1775 3350);
DISPLAY INVISIBLE (-1775 3350);
FORCEPROP 1 LAST BODY_TYPE PLUMBING
J 2
(-1775 3300);
DISPLAY 1.234043 (-1775 3300);
PAINT GREEN (-1775 3300);
DISPLAY INVISIBLE (-1775 3300);
FORCEPROP 1 LAST HDL_TAP TRUE
J 2
(-2100 3225);
DISPLAY 1.234043 (-2100 3225);
PAINT GREEN (-2100 3225);
DISPLAY INVISIBLE (-2100 3225);
FORCEPROP 1 LAST PATH I154
J 2
(-1773 3350);
DISPLAY 0.872340 (-1773 3350);
PAINT GREEN (-1773 3350);
DISPLAY INVISIBLE (-1773 3350);
FORCEADD TAP..6
R 2
(-1775 3450);
FORCEPROP 3 LASTPIN (-1825 3450) SIG_NAME M_H_DQS_DN<6>
J 0
(-1815 3460);
DISPLAY 0.659574 (-1815 3460);
PAINT MONO (-1815 3460);
DISPLAY INVISIBLE (-1815 3460);
FORCEPROP 1 LASTPIN (-1825 3450) BN 6
J 2
(-1775 3460);
DISPLAY 0.617021 (-1775 3460);
PAINT PINK (-1775 3460);
FORCEPROP 2 LAST CDS_LIB mstr_standard
J 0
(-1775 3450);
DISPLAY 0.787234 (-1775 3450);
PAINT MONO (-1775 3450);
DISPLAY INVISIBLE (-1775 3450);
FORCEPROP 1 LAST BODY_TYPE PLUMBING
J 2
(-1775 3400);
DISPLAY 1.234043 (-1775 3400);
PAINT GREEN (-1775 3400);
DISPLAY INVISIBLE (-1775 3400);
FORCEPROP 1 LAST HDL_TAP TRUE
J 2
(-2100 3325);
DISPLAY 1.234043 (-2100 3325);
PAINT GREEN (-2100 3325);
DISPLAY INVISIBLE (-2100 3325);
FORCEPROP 1 LAST PATH I155
J 2
(-1773 3450);
DISPLAY 0.872340 (-1773 3450);
PAINT GREEN (-1773 3450);
DISPLAY INVISIBLE (-1773 3450);
FORCEADD GND..1
R 2
(-175 550);
FORCEPROP 3 LASTPIN (-175 600) SIG_NAME GND\g
J 0
(-165 610);
DISPLAY 0.659574 (-165 610);
PAINT MONO (-165 610);
DISPLAY INVISIBLE (-165 610);
FORCEPROP 1 LAST VOLTAGE 0
J 0
(-175 550);
PAINT SKYBLUE (-175 550);
DISPLAY INVISIBLE (-175 550);
FORCEPROP 2 LAST CDS_LIB mstr_symbols
J 0
(-175 550);
DISPLAY 0.787234 (-175 550);
PAINT MONO (-175 550);
DISPLAY INVISIBLE (-175 550);
FORCEPROP 1 LAST SIZE 1B
J 2
(-250 500);
DISPLAY 1.170213 (-250 500);
PAINT GREEN (-250 500);
DISPLAY INVISIBLE (-250 500);
FORCEPROP 2 LAST BOM_COST MEM
J 0
(-175 555);
PAINT ORANGE (-175 555);
DISPLAY INVISIBLE (-175 555);
FORCEPROP 1 LAST BODY_TYPE PLUMBING
J 2
(-130 507);
DISPLAY 0.340426 (-130 507);
PAINT GREEN (-130 507);
DISPLAY INVISIBLE (-130 507);
FORCEPROP 1 LAST PATH I156
J 2
(-250 550);
DISPLAY 0.872340 (-250 550);
PAINT AQUA (-250 550);
DISPLAY INVISIBLE (-250 550);
FORCEPROP 2 LAST ROOM DDR4_GH_G
J 0
(-175 555);
PAINT ORANGE (-175 555);
DISPLAY INVISIBLE (-175 555);
FORCEPROP 1 LAST HDL_POWER GND
J 2
(-175 700);
DISPLAY 0.553191 (-175 700);
PAINT GREEN (-175 700);
DISPLAY INVISIBLE (-175 700);
FORCEADD TAP..6
R 2
(-1975 3800);
FORCEPROP 3 LASTPIN (-2025 3800) SIG_NAME M_H_DQS_DP<9>
J 0
(-2015 3810);
DISPLAY 0.659574 (-2015 3810);
PAINT MONO (-2015 3810);
DISPLAY INVISIBLE (-2015 3810);
FORCEPROP 1 LASTPIN (-2025 3800) BN 9
J 2
(-1975 3810);
DISPLAY 0.617021 (-1975 3810);
PAINT PINK (-1975 3810);
FORCEPROP 2 LAST CDS_LIB mstr_standard
J 0
(-1975 3800);
DISPLAY 0.787234 (-1975 3800);
PAINT MONO (-1975 3800);
DISPLAY INVISIBLE (-1975 3800);
FORCEPROP 1 LAST BODY_TYPE PLUMBING
J 2
(-1975 3750);
DISPLAY 1.234043 (-1975 3750);
PAINT GREEN (-1975 3750);
DISPLAY INVISIBLE (-1975 3750);
FORCEPROP 1 LAST HDL_TAP TRUE
J 2
(-2300 3675);
DISPLAY 1.234043 (-2300 3675);
PAINT GREEN (-2300 3675);
DISPLAY INVISIBLE (-2300 3675);
FORCEPROP 1 LAST PATH I157
J 2
(-1973 3800);
DISPLAY 0.872340 (-1973 3800);
PAINT GREEN (-1973 3800);
DISPLAY INVISIBLE (-1973 3800);
FORCEADD TAP..6
R 2
(-1975 3600);
FORCEPROP 3 LASTPIN (-2025 3600) SIG_NAME M_H_DQS_DP<7>
J 0
(-2015 3610);
DISPLAY 0.659574 (-2015 3610);
PAINT MONO (-2015 3610);
DISPLAY INVISIBLE (-2015 3610);
FORCEPROP 1 LASTPIN (-2025 3600) BN 7
J 2
(-1975 3610);
DISPLAY 0.617021 (-1975 3610);
PAINT PINK (-1975 3610);
FORCEPROP 2 LAST CDS_LIB mstr_standard
J 0
(-1975 3600);
DISPLAY 0.787234 (-1975 3600);
PAINT MONO (-1975 3600);
DISPLAY INVISIBLE (-1975 3600);
FORCEPROP 1 LAST BODY_TYPE PLUMBING
J 2
(-1975 3550);
DISPLAY 1.234043 (-1975 3550);
PAINT GREEN (-1975 3550);
DISPLAY INVISIBLE (-1975 3550);
FORCEPROP 1 LAST HDL_TAP TRUE
J 2
(-2300 3475);
DISPLAY 1.234043 (-2300 3475);
PAINT GREEN (-2300 3475);
DISPLAY INVISIBLE (-2300 3475);
FORCEPROP 1 LAST PATH I158
J 2
(-1973 3600);
DISPLAY 0.872340 (-1973 3600);
PAINT GREEN (-1973 3600);
DISPLAY INVISIBLE (-1973 3600);
FORCEADD TAP..6
R 2
(-1975 3700);
FORCEPROP 3 LASTPIN (-2025 3700) SIG_NAME M_H_DQS_DP<8>
J 0
(-2015 3710);
DISPLAY 0.659574 (-2015 3710);
PAINT MONO (-2015 3710);
DISPLAY INVISIBLE (-2015 3710);
FORCEPROP 1 LASTPIN (-2025 3700) BN 8
J 2
(-1975 3710);
DISPLAY 0.617021 (-1975 3710);
PAINT PINK (-1975 3710);
FORCEPROP 2 LAST CDS_LIB mstr_standard
J 0
(-1975 3700);
DISPLAY 0.787234 (-1975 3700);
PAINT MONO (-1975 3700);
DISPLAY INVISIBLE (-1975 3700);
FORCEPROP 1 LAST BODY_TYPE PLUMBING
J 2
(-1975 3650);
DISPLAY 1.234043 (-1975 3650);
PAINT GREEN (-1975 3650);
DISPLAY INVISIBLE (-1975 3650);
FORCEPROP 1 LAST HDL_TAP TRUE
J 2
(-2300 3575);
DISPLAY 1.234043 (-2300 3575);
PAINT GREEN (-2300 3575);
DISPLAY INVISIBLE (-2300 3575);
FORCEPROP 1 LAST PATH I159
J 2
(-1973 3700);
DISPLAY 0.872340 (-1973 3700);
PAINT GREEN (-1973 3700);
DISPLAY INVISIBLE (-1973 3700);
FORCEADD OFFPAGE..1
(-6625 2650);
FORCEPROP 2 LAST $XR0 58 
J 0
(-6846 2650);
DISPLAY 0.638298 (-6846 2650);
PAINT MONO (-6846 2650);
FORCEPROP 2 LAST $XR1 79 
J 0
(-6936 2650);
DISPLAY 0.638298 (-6936 2650);
PAINT MONO (-6936 2650);
FORCEPROP 2 LAST CDS_LIB mstr_standard
J 0
(-6625 2650);
DISPLAY 0.787234 (-6625 2650);
PAINT MONO (-6625 2650);
DISPLAY INVISIBLE (-6625 2650);
FORCEPROP 1 LAST OFFPAGE TRUE
J 0
(-6300 2525);
DISPLAY 0.936170 (-6300 2525);
PAINT GREEN (-6300 2525);
DISPLAY INVISIBLE (-6300 2525);
FORCEPROP 1 LAST COMMENT_BODY TRUE
J 0
(-6500 2550);
DISPLAY 0.936170 (-6500 2550);
PAINT GREEN (-6500 2550);
DISPLAY INVISIBLE (-6500 2550);
FORCEPROP 2 LAST PATH I16
J 0
(-6875 2700);
DISPLAY 1.021277 (-6875 2700);
PAINT ORANGE (-6875 2700);
DISPLAY INVISIBLE (-6875 2700);
FORCEADD TAP..6
R 2
(-1975 4000);
FORCEPROP 3 LASTPIN (-2025 4000) SIG_NAME M_H_DQS_DP<11>
J 0
(-2015 4010);
DISPLAY 0.659574 (-2015 4010);
PAINT MONO (-2015 4010);
DISPLAY INVISIBLE (-2015 4010);
FORCEPROP 1 LASTPIN (-2025 4000) BN 11
J 2
(-1975 4010);
DISPLAY 0.617021 (-1975 4010);
PAINT PINK (-1975 4010);
FORCEPROP 2 LAST CDS_LIB mstr_standard
J 0
(-1975 4000);
DISPLAY 0.787234 (-1975 4000);
PAINT MONO (-1975 4000);
DISPLAY INVISIBLE (-1975 4000);
FORCEPROP 1 LAST BODY_TYPE PLUMBING
J 2
(-1975 3950);
DISPLAY 1.234043 (-1975 3950);
PAINT GREEN (-1975 3950);
DISPLAY INVISIBLE (-1975 3950);
FORCEPROP 1 LAST HDL_TAP TRUE
J 2
(-2300 3875);
DISPLAY 1.234043 (-2300 3875);
PAINT GREEN (-2300 3875);
DISPLAY INVISIBLE (-2300 3875);
FORCEPROP 1 LAST PATH I160
J 2
(-1973 4000);
DISPLAY 0.872340 (-1973 4000);
PAINT GREEN (-1973 4000);
DISPLAY INVISIBLE (-1973 4000);
FORCEADD TAP..6
R 2
(-1975 3900);
FORCEPROP 3 LASTPIN (-2025 3900) SIG_NAME M_H_DQS_DP<10>
J 0
(-2015 3910);
DISPLAY 0.659574 (-2015 3910);
PAINT MONO (-2015 3910);
DISPLAY INVISIBLE (-2015 3910);
FORCEPROP 1 LASTPIN (-2025 3900) BN 10
J 2
(-1975 3910);
DISPLAY 0.617021 (-1975 3910);
PAINT PINK (-1975 3910);
FORCEPROP 2 LAST CDS_LIB mstr_standard
J 0
(-1975 3900);
DISPLAY 0.787234 (-1975 3900);
PAINT MONO (-1975 3900);
DISPLAY INVISIBLE (-1975 3900);
FORCEPROP 1 LAST BODY_TYPE PLUMBING
J 2
(-1975 3850);
DISPLAY 1.234043 (-1975 3850);
PAINT GREEN (-1975 3850);
DISPLAY INVISIBLE (-1975 3850);
FORCEPROP 1 LAST HDL_TAP TRUE
J 2
(-2300 3775);
DISPLAY 1.234043 (-2300 3775);
PAINT GREEN (-2300 3775);
DISPLAY INVISIBLE (-2300 3775);
FORCEPROP 1 LAST PATH I161
J 2
(-1973 3900);
DISPLAY 0.872340 (-1973 3900);
PAINT GREEN (-1973 3900);
DISPLAY INVISIBLE (-1973 3900);
FORCEADD TAP..6
R 2
(-1775 3650);
FORCEPROP 3 LASTPIN (-1825 3650) SIG_NAME M_H_DQS_DN<8>
J 0
(-1815 3660);
DISPLAY 0.659574 (-1815 3660);
PAINT MONO (-1815 3660);
DISPLAY INVISIBLE (-1815 3660);
FORCEPROP 1 LASTPIN (-1825 3650) BN 8
J 2
(-1775 3660);
DISPLAY 0.617021 (-1775 3660);
PAINT PINK (-1775 3660);
FORCEPROP 2 LAST CDS_LIB mstr_standard
J 0
(-1775 3650);
DISPLAY 0.787234 (-1775 3650);
PAINT MONO (-1775 3650);
DISPLAY INVISIBLE (-1775 3650);
FORCEPROP 1 LAST BODY_TYPE PLUMBING
J 2
(-1775 3600);
DISPLAY 1.234043 (-1775 3600);
PAINT GREEN (-1775 3600);
DISPLAY INVISIBLE (-1775 3600);
FORCEPROP 1 LAST HDL_TAP TRUE
J 2
(-2100 3525);
DISPLAY 1.234043 (-2100 3525);
PAINT GREEN (-2100 3525);
DISPLAY INVISIBLE (-2100 3525);
FORCEPROP 1 LAST PATH I162
J 2
(-1773 3650);
DISPLAY 0.872340 (-1773 3650);
PAINT GREEN (-1773 3650);
DISPLAY INVISIBLE (-1773 3650);
FORCEADD TAP..6
R 2
(-1775 3550);
FORCEPROP 3 LASTPIN (-1825 3550) SIG_NAME M_H_DQS_DN<7>
J 0
(-1815 3560);
DISPLAY 0.659574 (-1815 3560);
PAINT MONO (-1815 3560);
DISPLAY INVISIBLE (-1815 3560);
FORCEPROP 1 LASTPIN (-1825 3550) BN 7
J 2
(-1775 3560);
DISPLAY 0.617021 (-1775 3560);
PAINT PINK (-1775 3560);
FORCEPROP 2 LAST CDS_LIB mstr_standard
J 0
(-1775 3550);
DISPLAY 0.787234 (-1775 3550);
PAINT MONO (-1775 3550);
DISPLAY INVISIBLE (-1775 3550);
FORCEPROP 1 LAST BODY_TYPE PLUMBING
J 2
(-1775 3500);
DISPLAY 1.234043 (-1775 3500);
PAINT GREEN (-1775 3500);
DISPLAY INVISIBLE (-1775 3500);
FORCEPROP 1 LAST HDL_TAP TRUE
J 2
(-2100 3425);
DISPLAY 1.234043 (-2100 3425);
PAINT GREEN (-2100 3425);
DISPLAY INVISIBLE (-2100 3425);
FORCEPROP 1 LAST PATH I163
J 2
(-1773 3550);
DISPLAY 0.872340 (-1773 3550);
PAINT GREEN (-1773 3550);
DISPLAY INVISIBLE (-1773 3550);
FORCEADD TAP..6
R 2
(-1775 3750);
FORCEPROP 3 LASTPIN (-1825 3750) SIG_NAME M_H_DQS_DN<9>
J 0
(-1815 3760);
DISPLAY 0.659574 (-1815 3760);
PAINT MONO (-1815 3760);
DISPLAY INVISIBLE (-1815 3760);
FORCEPROP 1 LASTPIN (-1825 3750) BN 9
J 2
(-1775 3760);
DISPLAY 0.617021 (-1775 3760);
PAINT PINK (-1775 3760);
FORCEPROP 2 LAST CDS_LIB mstr_standard
J 0
(-1775 3750);
DISPLAY 0.787234 (-1775 3750);
PAINT MONO (-1775 3750);
DISPLAY INVISIBLE (-1775 3750);
FORCEPROP 1 LAST BODY_TYPE PLUMBING
J 2
(-1775 3700);
DISPLAY 1.234043 (-1775 3700);
PAINT GREEN (-1775 3700);
DISPLAY INVISIBLE (-1775 3700);
FORCEPROP 1 LAST HDL_TAP TRUE
J 2
(-2100 3625);
DISPLAY 1.234043 (-2100 3625);
PAINT GREEN (-2100 3625);
DISPLAY INVISIBLE (-2100 3625);
FORCEPROP 1 LAST PATH I164
J 2
(-1773 3750);
DISPLAY 0.872340 (-1773 3750);
PAINT GREEN (-1773 3750);
DISPLAY INVISIBLE (-1773 3750);
FORCEADD TAP..6
R 2
(-1775 3850);
FORCEPROP 3 LASTPIN (-1825 3850) SIG_NAME M_H_DQS_DN<10>
J 0
(-1815 3860);
DISPLAY 0.659574 (-1815 3860);
PAINT MONO (-1815 3860);
DISPLAY INVISIBLE (-1815 3860);
FORCEPROP 1 LASTPIN (-1825 3850) BN 10
J 2
(-1775 3860);
DISPLAY 0.617021 (-1775 3860);
PAINT PINK (-1775 3860);
FORCEPROP 2 LAST CDS_LIB mstr_standard
J 0
(-1775 3850);
DISPLAY 0.787234 (-1775 3850);
PAINT MONO (-1775 3850);
DISPLAY INVISIBLE (-1775 3850);
FORCEPROP 1 LAST BODY_TYPE PLUMBING
J 2
(-1775 3800);
DISPLAY 1.234043 (-1775 3800);
PAINT GREEN (-1775 3800);
DISPLAY INVISIBLE (-1775 3800);
FORCEPROP 1 LAST HDL_TAP TRUE
J 2
(-2100 3725);
DISPLAY 1.234043 (-2100 3725);
PAINT GREEN (-2100 3725);
DISPLAY INVISIBLE (-2100 3725);
FORCEPROP 1 LAST PATH I165
J 2
(-1773 3850);
DISPLAY 0.872340 (-1773 3850);
PAINT GREEN (-1773 3850);
DISPLAY INVISIBLE (-1773 3850);
FORCEADD TAP..6
R 2
(-1775 3950);
FORCEPROP 3 LASTPIN (-1825 3950) SIG_NAME M_H_DQS_DN<11>
J 0
(-1815 3960);
DISPLAY 0.659574 (-1815 3960);
PAINT MONO (-1815 3960);
DISPLAY INVISIBLE (-1815 3960);
FORCEPROP 1 LASTPIN (-1825 3950) BN 11
J 2
(-1775 3960);
DISPLAY 0.617021 (-1775 3960);
PAINT PINK (-1775 3960);
FORCEPROP 2 LAST CDS_LIB mstr_standard
J 0
(-1775 3950);
DISPLAY 0.787234 (-1775 3950);
PAINT MONO (-1775 3950);
DISPLAY INVISIBLE (-1775 3950);
FORCEPROP 1 LAST BODY_TYPE PLUMBING
J 2
(-1775 3900);
DISPLAY 1.234043 (-1775 3900);
PAINT GREEN (-1775 3900);
DISPLAY INVISIBLE (-1775 3900);
FORCEPROP 1 LAST HDL_TAP TRUE
J 2
(-2100 3825);
DISPLAY 1.234043 (-2100 3825);
PAINT GREEN (-2100 3825);
DISPLAY INVISIBLE (-2100 3825);
FORCEPROP 1 LAST PATH I166
J 2
(-1773 3950);
DISPLAY 0.872340 (-1773 3950);
PAINT GREEN (-1773 3950);
DISPLAY INVISIBLE (-1773 3950);
FORCEADD TAP..6
R 2
(-1775 4050);
FORCEPROP 3 LASTPIN (-1825 4050) SIG_NAME M_H_DQS_DN<12>
J 0
(-1815 4060);
DISPLAY 0.659574 (-1815 4060);
PAINT MONO (-1815 4060);
DISPLAY INVISIBLE (-1815 4060);
FORCEPROP 1 LASTPIN (-1825 4050) BN 12
J 2
(-1775 4060);
DISPLAY 0.617021 (-1775 4060);
PAINT PINK (-1775 4060);
FORCEPROP 2 LAST CDS_LIB mstr_standard
J 0
(-1775 4050);
DISPLAY 0.787234 (-1775 4050);
PAINT MONO (-1775 4050);
DISPLAY INVISIBLE (-1775 4050);
FORCEPROP 1 LAST BODY_TYPE PLUMBING
J 2
(-1775 4000);
DISPLAY 1.234043 (-1775 4000);
PAINT GREEN (-1775 4000);
DISPLAY INVISIBLE (-1775 4000);
FORCEPROP 1 LAST HDL_TAP TRUE
J 2
(-2100 3925);
DISPLAY 1.234043 (-2100 3925);
PAINT GREEN (-2100 3925);
DISPLAY INVISIBLE (-2100 3925);
FORCEPROP 1 LAST PATH I167
J 2
(-1773 4050);
DISPLAY 0.872340 (-1773 4050);
PAINT GREEN (-1773 4050);
DISPLAY INVISIBLE (-1773 4050);
FORCEADD TAP..6
R 2
(-1975 4300);
FORCEPROP 3 LASTPIN (-2025 4300) SIG_NAME M_H_DQS_DP<14>
J 0
(-2015 4310);
DISPLAY 0.659574 (-2015 4310);
PAINT MONO (-2015 4310);
DISPLAY INVISIBLE (-2015 4310);
FORCEPROP 1 LASTPIN (-2025 4300) BN 14
J 2
(-1975 4310);
DISPLAY 0.617021 (-1975 4310);
PAINT PINK (-1975 4310);
FORCEPROP 2 LAST CDS_LIB mstr_standard
J 0
(-1975 4300);
DISPLAY 0.787234 (-1975 4300);
PAINT MONO (-1975 4300);
DISPLAY INVISIBLE (-1975 4300);
FORCEPROP 1 LAST BODY_TYPE PLUMBING
J 2
(-1975 4250);
DISPLAY 1.234043 (-1975 4250);
PAINT GREEN (-1975 4250);
DISPLAY INVISIBLE (-1975 4250);
FORCEPROP 1 LAST HDL_TAP TRUE
J 2
(-2300 4175);
DISPLAY 1.234043 (-2300 4175);
PAINT GREEN (-2300 4175);
DISPLAY INVISIBLE (-2300 4175);
FORCEPROP 1 LAST PATH I168
J 2
(-1973 4300);
DISPLAY 0.872340 (-1973 4300);
PAINT GREEN (-1973 4300);
DISPLAY INVISIBLE (-1973 4300);
FORCEADD TAP..6
R 2
(-1975 4200);
FORCEPROP 3 LASTPIN (-2025 4200) SIG_NAME M_H_DQS_DP<13>
J 0
(-2015 4210);
DISPLAY 0.659574 (-2015 4210);
PAINT MONO (-2015 4210);
DISPLAY INVISIBLE (-2015 4210);
FORCEPROP 1 LASTPIN (-2025 4200) BN 13
J 2
(-1975 4210);
DISPLAY 0.617021 (-1975 4210);
PAINT PINK (-1975 4210);
FORCEPROP 2 LAST CDS_LIB mstr_standard
J 0
(-1975 4200);
DISPLAY 0.787234 (-1975 4200);
PAINT MONO (-1975 4200);
DISPLAY INVISIBLE (-1975 4200);
FORCEPROP 1 LAST BODY_TYPE PLUMBING
J 2
(-1975 4150);
DISPLAY 1.234043 (-1975 4150);
PAINT GREEN (-1975 4150);
DISPLAY INVISIBLE (-1975 4150);
FORCEPROP 1 LAST HDL_TAP TRUE
J 2
(-2300 4075);
DISPLAY 1.234043 (-2300 4075);
PAINT GREEN (-2300 4075);
DISPLAY INVISIBLE (-2300 4075);
FORCEPROP 1 LAST PATH I169
J 2
(-1973 4200);
DISPLAY 0.872340 (-1973 4200);
PAINT GREEN (-1973 4200);
DISPLAY INVISIBLE (-1973 4200);
FORCEADD OFFPAGE..1
(-6625 2900);
FORCEPROP 2 LAST $XR0 58 
J 0
(-6846 2900);
DISPLAY 0.638298 (-6846 2900);
PAINT MONO (-6846 2900);
FORCEPROP 2 LAST $XR1 79 
J 0
(-6936 2900);
DISPLAY 0.638298 (-6936 2900);
PAINT MONO (-6936 2900);
FORCEPROP 2 LAST CDS_LIB mstr_standard
J 0
(-6625 2900);
DISPLAY 0.787234 (-6625 2900);
PAINT MONO (-6625 2900);
DISPLAY INVISIBLE (-6625 2900);
FORCEPROP 1 LAST OFFPAGE TRUE
J 0
(-6300 2775);
DISPLAY 0.936170 (-6300 2775);
PAINT GREEN (-6300 2775);
DISPLAY INVISIBLE (-6300 2775);
FORCEPROP 1 LAST COMMENT_BODY TRUE
J 0
(-6500 2800);
DISPLAY 0.936170 (-6500 2800);
PAINT GREEN (-6500 2800);
DISPLAY INVISIBLE (-6500 2800);
FORCEPROP 2 LAST PATH I17
J 0
(-6875 2950);
DISPLAY 1.021277 (-6875 2950);
PAINT ORANGE (-6875 2950);
DISPLAY INVISIBLE (-6875 2950);
FORCEADD TAP..6
R 2
(-1975 4100);
FORCEPROP 3 LASTPIN (-2025 4100) SIG_NAME M_H_DQS_DP<12>
J 0
(-2015 4110);
DISPLAY 0.659574 (-2015 4110);
PAINT MONO (-2015 4110);
DISPLAY INVISIBLE (-2015 4110);
FORCEPROP 1 LASTPIN (-2025 4100) BN 12
J 2
(-1975 4110);
DISPLAY 0.617021 (-1975 4110);
PAINT PINK (-1975 4110);
FORCEPROP 2 LAST CDS_LIB mstr_standard
J 0
(-1975 4100);
DISPLAY 0.787234 (-1975 4100);
PAINT MONO (-1975 4100);
DISPLAY INVISIBLE (-1975 4100);
FORCEPROP 1 LAST BODY_TYPE PLUMBING
J 2
(-1975 4050);
DISPLAY 1.234043 (-1975 4050);
PAINT GREEN (-1975 4050);
DISPLAY INVISIBLE (-1975 4050);
FORCEPROP 1 LAST HDL_TAP TRUE
J 2
(-2300 3975);
DISPLAY 1.234043 (-2300 3975);
PAINT GREEN (-2300 3975);
DISPLAY INVISIBLE (-2300 3975);
FORCEPROP 1 LAST PATH I170
J 2
(-1973 4100);
DISPLAY 0.872340 (-1973 4100);
PAINT GREEN (-1973 4100);
DISPLAY INVISIBLE (-1973 4100);
FORCEADD TAP..6
R 2
(-1975 4400);
FORCEPROP 3 LASTPIN (-2025 4400) SIG_NAME M_H_DQS_DP<15>
J 0
(-2015 4410);
DISPLAY 0.659574 (-2015 4410);
PAINT MONO (-2015 4410);
DISPLAY INVISIBLE (-2015 4410);
FORCEPROP 1 LASTPIN (-2025 4400) BN 15
J 2
(-1975 4410);
DISPLAY 0.617021 (-1975 4410);
PAINT PINK (-1975 4410);
FORCEPROP 2 LAST CDS_LIB mstr_standard
J 0
(-1975 4400);
DISPLAY 0.787234 (-1975 4400);
PAINT MONO (-1975 4400);
DISPLAY INVISIBLE (-1975 4400);
FORCEPROP 1 LAST BODY_TYPE PLUMBING
J 2
(-1975 4350);
DISPLAY 1.234043 (-1975 4350);
PAINT GREEN (-1975 4350);
DISPLAY INVISIBLE (-1975 4350);
FORCEPROP 1 LAST HDL_TAP TRUE
J 2
(-2300 4275);
DISPLAY 1.234043 (-2300 4275);
PAINT GREEN (-2300 4275);
DISPLAY INVISIBLE (-2300 4275);
FORCEPROP 1 LAST PATH I171
J 2
(-1973 4400);
DISPLAY 0.872340 (-1973 4400);
PAINT GREEN (-1973 4400);
DISPLAY INVISIBLE (-1973 4400);
FORCEADD TAP..6
R 2
(-1975 4500);
FORCEPROP 3 LASTPIN (-2025 4500) SIG_NAME M_H_DQS_DP<16>
J 0
(-2015 4510);
DISPLAY 0.659574 (-2015 4510);
PAINT MONO (-2015 4510);
DISPLAY INVISIBLE (-2015 4510);
FORCEPROP 1 LASTPIN (-2025 4500) BN 16
J 2
(-1975 4510);
DISPLAY 0.617021 (-1975 4510);
PAINT PINK (-1975 4510);
FORCEPROP 2 LAST CDS_LIB mstr_standard
J 0
(-1975 4500);
DISPLAY 0.787234 (-1975 4500);
PAINT MONO (-1975 4500);
DISPLAY INVISIBLE (-1975 4500);
FORCEPROP 1 LAST BODY_TYPE PLUMBING
J 2
(-1975 4450);
DISPLAY 1.234043 (-1975 4450);
PAINT GREEN (-1975 4450);
DISPLAY INVISIBLE (-1975 4450);
FORCEPROP 1 LAST HDL_TAP TRUE
J 2
(-2300 4375);
DISPLAY 1.234043 (-2300 4375);
PAINT GREEN (-2300 4375);
DISPLAY INVISIBLE (-2300 4375);
FORCEPROP 1 LAST PATH I172
J 2
(-1973 4500);
DISPLAY 0.872340 (-1973 4500);
PAINT GREEN (-1973 4500);
DISPLAY INVISIBLE (-1973 4500);
FORCEADD TAP..6
R 2
(-1775 4150);
FORCEPROP 3 LASTPIN (-1825 4150) SIG_NAME M_H_DQS_DN<13>
J 0
(-1815 4160);
DISPLAY 0.659574 (-1815 4160);
PAINT MONO (-1815 4160);
DISPLAY INVISIBLE (-1815 4160);
FORCEPROP 1 LASTPIN (-1825 4150) BN 13
J 2
(-1775 4160);
DISPLAY 0.617021 (-1775 4160);
PAINT PINK (-1775 4160);
FORCEPROP 2 LAST CDS_LIB mstr_standard
J 0
(-1775 4150);
DISPLAY 0.787234 (-1775 4150);
PAINT MONO (-1775 4150);
DISPLAY INVISIBLE (-1775 4150);
FORCEPROP 1 LAST BODY_TYPE PLUMBING
J 2
(-1775 4100);
DISPLAY 1.234043 (-1775 4100);
PAINT GREEN (-1775 4100);
DISPLAY INVISIBLE (-1775 4100);
FORCEPROP 1 LAST HDL_TAP TRUE
J 2
(-2100 4025);
DISPLAY 1.234043 (-2100 4025);
PAINT GREEN (-2100 4025);
DISPLAY INVISIBLE (-2100 4025);
FORCEPROP 1 LAST PATH I173
J 2
(-1773 4150);
DISPLAY 0.872340 (-1773 4150);
PAINT GREEN (-1773 4150);
DISPLAY INVISIBLE (-1773 4150);
FORCEADD TAP..6
R 2
(-1775 4250);
FORCEPROP 3 LASTPIN (-1825 4250) SIG_NAME M_H_DQS_DN<14>
J 0
(-1815 4260);
DISPLAY 0.659574 (-1815 4260);
PAINT MONO (-1815 4260);
DISPLAY INVISIBLE (-1815 4260);
FORCEPROP 1 LASTPIN (-1825 4250) BN 14
J 2
(-1775 4260);
DISPLAY 0.617021 (-1775 4260);
PAINT PINK (-1775 4260);
FORCEPROP 2 LAST CDS_LIB mstr_standard
J 0
(-1775 4250);
DISPLAY 0.787234 (-1775 4250);
PAINT MONO (-1775 4250);
DISPLAY INVISIBLE (-1775 4250);
FORCEPROP 1 LAST BODY_TYPE PLUMBING
J 2
(-1775 4200);
DISPLAY 1.234043 (-1775 4200);
PAINT GREEN (-1775 4200);
DISPLAY INVISIBLE (-1775 4200);
FORCEPROP 1 LAST HDL_TAP TRUE
J 2
(-2100 4125);
DISPLAY 1.234043 (-2100 4125);
PAINT GREEN (-2100 4125);
DISPLAY INVISIBLE (-2100 4125);
FORCEPROP 1 LAST PATH I174
J 2
(-1773 4250);
DISPLAY 0.872340 (-1773 4250);
PAINT GREEN (-1773 4250);
DISPLAY INVISIBLE (-1773 4250);
FORCEADD TAP..6
R 2
(-1775 4350);
FORCEPROP 3 LASTPIN (-1825 4350) SIG_NAME M_H_DQS_DN<15>
J 0
(-1815 4360);
DISPLAY 0.659574 (-1815 4360);
PAINT MONO (-1815 4360);
DISPLAY INVISIBLE (-1815 4360);
FORCEPROP 1 LASTPIN (-1825 4350) BN 15
J 2
(-1775 4360);
DISPLAY 0.617021 (-1775 4360);
PAINT PINK (-1775 4360);
FORCEPROP 2 LAST CDS_LIB mstr_standard
J 0
(-1775 4350);
DISPLAY 0.787234 (-1775 4350);
PAINT MONO (-1775 4350);
DISPLAY INVISIBLE (-1775 4350);
FORCEPROP 1 LAST BODY_TYPE PLUMBING
J 2
(-1775 4300);
DISPLAY 1.234043 (-1775 4300);
PAINT GREEN (-1775 4300);
DISPLAY INVISIBLE (-1775 4300);
FORCEPROP 1 LAST HDL_TAP TRUE
J 2
(-2100 4225);
DISPLAY 1.234043 (-2100 4225);
PAINT GREEN (-2100 4225);
DISPLAY INVISIBLE (-2100 4225);
FORCEPROP 1 LAST PATH I175
J 2
(-1773 4350);
DISPLAY 0.872340 (-1773 4350);
PAINT GREEN (-1773 4350);
DISPLAY INVISIBLE (-1773 4350);
FORCEADD TAP..6
R 2
(-1775 4450);
FORCEPROP 3 LASTPIN (-1825 4450) SIG_NAME M_H_DQS_DN<16>
J 0
(-1815 4460);
DISPLAY 0.659574 (-1815 4460);
PAINT MONO (-1815 4460);
DISPLAY INVISIBLE (-1815 4460);
FORCEPROP 1 LASTPIN (-1825 4450) BN 16
J 2
(-1775 4460);
DISPLAY 0.617021 (-1775 4460);
PAINT PINK (-1775 4460);
FORCEPROP 2 LAST CDS_LIB mstr_standard
J 0
(-1775 4450);
DISPLAY 0.787234 (-1775 4450);
PAINT MONO (-1775 4450);
DISPLAY INVISIBLE (-1775 4450);
FORCEPROP 1 LAST BODY_TYPE PLUMBING
J 2
(-1775 4400);
DISPLAY 1.234043 (-1775 4400);
PAINT GREEN (-1775 4400);
DISPLAY INVISIBLE (-1775 4400);
FORCEPROP 1 LAST HDL_TAP TRUE
J 2
(-2100 4325);
DISPLAY 1.234043 (-2100 4325);
PAINT GREEN (-2100 4325);
DISPLAY INVISIBLE (-2100 4325);
FORCEPROP 1 LAST PATH I176
J 2
(-1773 4450);
DISPLAY 0.872340 (-1773 4450);
PAINT GREEN (-1773 4450);
DISPLAY INVISIBLE (-1773 4450);
FORCEADD TAP..6
R 2
(-1775 4550);
FORCEPROP 3 LASTPIN (-1825 4550) SIG_NAME M_H_DQS_DN<17>
J 0
(-1815 4560);
DISPLAY 0.659574 (-1815 4560);
PAINT MONO (-1815 4560);
DISPLAY INVISIBLE (-1815 4560);
FORCEPROP 1 LASTPIN (-1825 4550) BN 17
J 2
(-1775 4560);
DISPLAY 0.617021 (-1775 4560);
PAINT PINK (-1775 4560);
FORCEPROP 2 LAST CDS_LIB mstr_standard
J 2
(-1775 4550);
DISPLAY 0.787234 (-1775 4550);
PAINT MONO (-1775 4550);
DISPLAY INVISIBLE (-1775 4550);
FORCEPROP 1 LAST BODY_TYPE PLUMBING
J 2
(-1775 4500);
DISPLAY 1.234043 (-1775 4500);
PAINT GREEN (-1775 4500);
DISPLAY INVISIBLE (-1775 4500);
FORCEPROP 1 LAST HDL_TAP TRUE
J 2
(-2100 4425);
DISPLAY 1.234043 (-2100 4425);
PAINT GREEN (-2100 4425);
DISPLAY INVISIBLE (-2100 4425);
FORCEPROP 1 LAST PATH I177
J 2
(-1773 4550);
DISPLAY 0.872340 (-1773 4550);
PAINT GREEN (-1773 4550);
DISPLAY INVISIBLE (-1773 4550);
FORCEADD TAP..6
R 2
(-1975 4600);
FORCEPROP 3 LASTPIN (-2025 4600) SIG_NAME M_H_DQS_DP<17>
J 0
(-2015 4610);
DISPLAY 0.659574 (-2015 4610);
PAINT MONO (-2015 4610);
DISPLAY INVISIBLE (-2015 4610);
FORCEPROP 1 LASTPIN (-2025 4600) BN 17
J 2
(-1975 4610);
DISPLAY 0.617021 (-1975 4610);
PAINT PINK (-1975 4610);
FORCEPROP 2 LAST CDS_LIB mstr_standard
J 2
(-1975 4600);
DISPLAY 0.787234 (-1975 4600);
PAINT MONO (-1975 4600);
DISPLAY INVISIBLE (-1975 4600);
FORCEPROP 1 LAST BODY_TYPE PLUMBING
J 2
(-1975 4550);
DISPLAY 1.234043 (-1975 4550);
PAINT GREEN (-1975 4550);
DISPLAY INVISIBLE (-1975 4550);
FORCEPROP 1 LAST HDL_TAP TRUE
J 2
(-2300 4475);
DISPLAY 1.234043 (-2300 4475);
PAINT GREEN (-2300 4475);
DISPLAY INVISIBLE (-2300 4475);
FORCEPROP 1 LAST PATH I178
J 2
(-1973 4600);
DISPLAY 0.872340 (-1973 4600);
PAINT GREEN (-1973 4600);
DISPLAY INVISIBLE (-1973 4600);
FORCEADD OFFPAGE..3
(-1075 4600);
FORCEPROP 2 LAST $XR0 58 
J 0
(-861 4600);
DISPLAY 0.638298 (-861 4600);
PAINT MONO (-861 4600);
FORCEPROP 2 LAST $XR1 79 
J 0
(-771 4600);
DISPLAY 0.638298 (-771 4600);
PAINT MONO (-771 4600);
FORCEPROP 2 LAST CDS_LIB mstr_standard
J 0
(-1075 4600);
DISPLAY 0.787234 (-1075 4600);
PAINT MONO (-1075 4600);
DISPLAY INVISIBLE (-1075 4600);
FORCEPROP 1 LAST OFFPAGE TRUE
J 0
(-750 4475);
DISPLAY 0.936170 (-750 4475);
PAINT GREEN (-750 4475);
DISPLAY INVISIBLE (-750 4475);
FORCEPROP 1 LAST COMMENT_BODY TRUE
J 0
(-1125 4500);
DISPLAY 0.936170 (-1125 4500);
PAINT GREEN (-1125 4500);
DISPLAY INVISIBLE (-1125 4500);
FORCEPROP 2 LAST PATH I179
J 0
(-850 4650);
DISPLAY 1.021277 (-850 4650);
PAINT ORANGE (-850 4650);
DISPLAY INVISIBLE (-850 4650);
FORCEADD OFFPAGE..1
(-6625 2950);
FORCEPROP 2 LAST $XR0 58 
J 0
(-6846 2950);
DISPLAY 0.638298 (-6846 2950);
PAINT MONO (-6846 2950);
FORCEPROP 2 LAST $XR1 79 
J 0
(-6936 2950);
DISPLAY 0.638298 (-6936 2950);
PAINT MONO (-6936 2950);
FORCEPROP 2 LAST CDS_LIB mstr_standard
J 0
(-6625 2950);
DISPLAY 0.787234 (-6625 2950);
PAINT MONO (-6625 2950);
DISPLAY INVISIBLE (-6625 2950);
FORCEPROP 1 LAST OFFPAGE TRUE
J 0
(-6300 2825);
DISPLAY 0.936170 (-6300 2825);
PAINT GREEN (-6300 2825);
DISPLAY INVISIBLE (-6300 2825);
FORCEPROP 1 LAST COMMENT_BODY TRUE
J 0
(-6500 2850);
DISPLAY 0.936170 (-6500 2850);
PAINT GREEN (-6500 2850);
DISPLAY INVISIBLE (-6500 2850);
FORCEPROP 2 LAST PATH I18
J 0
(-6875 3000);
DISPLAY 1.021277 (-6875 3000);
PAINT ORANGE (-6875 3000);
DISPLAY INVISIBLE (-6875 3000);
FORCEADD OFFPAGE..3
(-1075 4650);
FORCEPROP 2 LAST $XR0 58 
J 0
(-861 4650);
DISPLAY 0.638298 (-861 4650);
PAINT MONO (-861 4650);
FORCEPROP 2 LAST $XR1 79 
J 0
(-771 4650);
DISPLAY 0.638298 (-771 4650);
PAINT MONO (-771 4650);
FORCEPROP 2 LAST CDS_LIB mstr_standard
J 0
(-1075 4650);
DISPLAY 0.787234 (-1075 4650);
PAINT MONO (-1075 4650);
DISPLAY INVISIBLE (-1075 4650);
FORCEPROP 1 LAST OFFPAGE TRUE
J 0
(-750 4525);
DISPLAY 0.936170 (-750 4525);
PAINT GREEN (-750 4525);
DISPLAY INVISIBLE (-750 4525);
FORCEPROP 1 LAST COMMENT_BODY TRUE
J 0
(-1125 4550);
DISPLAY 0.936170 (-1125 4550);
PAINT GREEN (-1125 4550);
DISPLAY INVISIBLE (-1125 4550);
FORCEPROP 2 LAST PATH I180
J 0
(-850 4700);
DISPLAY 1.021277 (-850 4700);
PAINT ORANGE (-850 4700);
DISPLAY INVISIBLE (-850 4700);
FORCEADD P12V_NVDIMM_GHJ..1
(-2375 2425);
FORCEPROP 3 LASTPIN (-2375 2375) SIG_NAME P12V_NVDIMM_GHJ\g
J 0
(-2365 2385);
DISPLAY 0.659574 (-2365 2385);
PAINT MONO (-2365 2385);
DISPLAY INVISIBLE (-2365 2385);
FORCEPROP 1 LAST VOLTAGE 12.0
J 0
(-2420 2382);
DISPLAY 0.340426 (-2420 2382);
PAINT SKYBLUE (-2420 2382);
DISPLAY INVISIBLE (-2420 2382);
FORCEPROP 2 LAST CDS_LIB mstr_symbols
J 0
(-2375 2425);
PAINT ORANGE (-2375 2425);
DISPLAY INVISIBLE (-2375 2425);
FORCEPROP 1 LAST BODY_TYPE PLUMBING
J 0
(-2420 2382);
DISPLAY 0.340426 (-2420 2382);
PAINT GREEN (-2420 2382);
DISPLAY INVISIBLE (-2420 2382);
FORCEPROP 1 LAST PATH I181
J 0
(-2325 2450);
DISPLAY 0.872340 (-2325 2450);
PAINT AQUA (-2325 2450);
DISPLAY INVISIBLE (-2325 2450);
FORCEPROP 1 LAST HDL_POWER P12V_NVDIMM_GHJ
J 1
(-2375 2475);
DISPLAY 0.872340 (-2375 2475);
PAINT GREEN (-2375 2475);
DISPLAY INVISIBLE (-2375 2475);
FORCEADD OFFPAGE..1
(-6625 3200);
FORCEPROP 2 LAST $XR0 58 
J 0
(-6846 3200);
DISPLAY 0.638298 (-6846 3200);
PAINT MONO (-6846 3200);
FORCEPROP 2 LAST $XR1 79 
J 0
(-6936 3200);
DISPLAY 0.638298 (-6936 3200);
PAINT MONO (-6936 3200);
FORCEPROP 2 LAST CDS_LIB mstr_standard
J 0
(-6625 3200);
DISPLAY 0.787234 (-6625 3200);
PAINT MONO (-6625 3200);
DISPLAY INVISIBLE (-6625 3200);
FORCEPROP 1 LAST OFFPAGE TRUE
J 0
(-6300 3075);
DISPLAY 0.936170 (-6300 3075);
PAINT GREEN (-6300 3075);
DISPLAY INVISIBLE (-6300 3075);
FORCEPROP 1 LAST COMMENT_BODY TRUE
J 0
(-6500 3100);
DISPLAY 0.936170 (-6500 3100);
PAINT GREEN (-6500 3100);
DISPLAY INVISIBLE (-6500 3100);
FORCEPROP 2 LAST PATH I19
J 0
(-6875 3250);
DISPLAY 1.021277 (-6875 3250);
PAINT ORANGE (-6875 3250);
DISPLAY INVISIBLE (-6875 3250);
FORCEADD OFFPAGE..1
(-7325 1200);
FORCEPROP 2 LAST $XR0 100 
J 0
(-7577 1200);
DISPLAY 0.638298 (-7577 1200);
PAINT MONO (-7577 1200);
FORCEPROP 2 LAST $XR1 79 
J 0
(-7667 1200);
DISPLAY 0.638298 (-7667 1200);
PAINT MONO (-7667 1200);
FORCEPROP 2 LAST CDS_LIB mstr_standard
J 0
(-7325 1200);
DISPLAY 0.787234 (-7325 1200);
PAINT MONO (-7325 1200);
DISPLAY INVISIBLE (-7325 1200);
FORCEPROP 1 LAST OFFPAGE TRUE
J 0
(-7000 1075);
DISPLAY 0.936170 (-7000 1075);
PAINT GREEN (-7000 1075);
DISPLAY INVISIBLE (-7000 1075);
FORCEPROP 1 LAST COMMENT_BODY TRUE
J 0
(-7200 1100);
DISPLAY 0.936170 (-7200 1100);
PAINT GREEN (-7200 1100);
DISPLAY INVISIBLE (-7200 1100);
FORCEPROP 2 LAST PATH I2
J 0
(-7525 1250);
DISPLAY 1.021277 (-7525 1250);
PAINT ORANGE (-7525 1250);
DISPLAY INVISIBLE (-7525 1250);
FORCEADD OFFPAGE..1
(-6625 3150);
FORCEPROP 2 LAST $XR0 58 
J 0
(-6846 3150);
DISPLAY 0.638298 (-6846 3150);
PAINT MONO (-6846 3150);
FORCEPROP 2 LAST $XR1 79 
J 0
(-6936 3150);
DISPLAY 0.638298 (-6936 3150);
PAINT MONO (-6936 3150);
FORCEPROP 2 LAST CDS_LIB mstr_standard
J 0
(-6625 3150);
DISPLAY 0.787234 (-6625 3150);
PAINT MONO (-6625 3150);
DISPLAY INVISIBLE (-6625 3150);
FORCEPROP 1 LAST OFFPAGE TRUE
J 0
(-6300 3025);
DISPLAY 0.936170 (-6300 3025);
PAINT GREEN (-6300 3025);
DISPLAY INVISIBLE (-6300 3025);
FORCEPROP 1 LAST COMMENT_BODY TRUE
J 0
(-6500 3050);
DISPLAY 0.936170 (-6500 3050);
PAINT GREEN (-6500 3050);
DISPLAY INVISIBLE (-6500 3050);
FORCEPROP 2 LAST PATH I20
J 0
(-6875 3200);
DISPLAY 1.021277 (-6875 3200);
PAINT ORANGE (-6875 3200);
DISPLAY INVISIBLE (-6875 3200);
FORCEADD OFFPAGE..1
(-6625 3350);
FORCEPROP 2 LAST $XR0 58 
J 0
(-6846 3350);
DISPLAY 0.638298 (-6846 3350);
PAINT MONO (-6846 3350);
FORCEPROP 2 LAST $XR1 79 
J 0
(-6936 3350);
DISPLAY 0.638298 (-6936 3350);
PAINT MONO (-6936 3350);
FORCEPROP 2 LAST CDS_LIB mstr_standard
J 0
(-6625 3350);
DISPLAY 0.787234 (-6625 3350);
PAINT MONO (-6625 3350);
DISPLAY INVISIBLE (-6625 3350);
FORCEPROP 1 LAST OFFPAGE TRUE
J 0
(-6300 3225);
DISPLAY 0.936170 (-6300 3225);
PAINT GREEN (-6300 3225);
DISPLAY INVISIBLE (-6300 3225);
FORCEPROP 1 LAST COMMENT_BODY TRUE
J 0
(-6500 3250);
DISPLAY 0.936170 (-6500 3250);
PAINT GREEN (-6500 3250);
DISPLAY INVISIBLE (-6500 3250);
FORCEPROP 2 LAST PATH I21
J 0
(-6875 3400);
DISPLAY 1.021277 (-6875 3400);
PAINT ORANGE (-6875 3400);
DISPLAY INVISIBLE (-6875 3400);
FORCEADD OFFPAGE..1
(-6625 3450);
FORCEPROP 2 LAST $XR0 58 
J 0
(-6846 3450);
DISPLAY 0.638298 (-6846 3450);
PAINT MONO (-6846 3450);
FORCEPROP 2 LAST $XR1 79 
J 0
(-6936 3450);
DISPLAY 0.638298 (-6936 3450);
PAINT MONO (-6936 3450);
FORCEPROP 2 LAST CDS_LIB mstr_standard
J 0
(-6625 3450);
DISPLAY 0.787234 (-6625 3450);
PAINT MONO (-6625 3450);
DISPLAY INVISIBLE (-6625 3450);
FORCEPROP 1 LAST OFFPAGE TRUE
J 0
(-6300 3325);
DISPLAY 0.936170 (-6300 3325);
PAINT GREEN (-6300 3325);
DISPLAY INVISIBLE (-6300 3325);
FORCEPROP 1 LAST COMMENT_BODY TRUE
J 0
(-6500 3350);
DISPLAY 0.936170 (-6500 3350);
PAINT GREEN (-6500 3350);
DISPLAY INVISIBLE (-6500 3350);
FORCEPROP 2 LAST PATH I22
J 0
(-6875 3500);
DISPLAY 1.021277 (-6875 3500);
PAINT ORANGE (-6875 3500);
DISPLAY INVISIBLE (-6875 3500);
FORCEADD OFFPAGE..1
(-6625 4400);
FORCEPROP 2 LAST $XR0 58 
J 0
(-6846 4400);
DISPLAY 0.638298 (-6846 4400);
PAINT MONO (-6846 4400);
FORCEPROP 2 LAST $XR1 79 
J 0
(-6936 4400);
DISPLAY 0.638298 (-6936 4400);
PAINT MONO (-6936 4400);
FORCEPROP 2 LAST CDS_LIB mstr_standard
J 0
(-6625 4400);
DISPLAY 0.787234 (-6625 4400);
PAINT MONO (-6625 4400);
DISPLAY INVISIBLE (-6625 4400);
FORCEPROP 1 LAST OFFPAGE TRUE
J 0
(-6300 4275);
DISPLAY 0.936170 (-6300 4275);
PAINT GREEN (-6300 4275);
DISPLAY INVISIBLE (-6300 4275);
FORCEPROP 1 LAST COMMENT_BODY TRUE
J 0
(-6500 4300);
DISPLAY 0.936170 (-6500 4300);
PAINT GREEN (-6500 4300);
DISPLAY INVISIBLE (-6500 4300);
FORCEPROP 2 LAST PATH I23
J 0
(-6875 4450);
DISPLAY 1.021277 (-6875 4450);
PAINT ORANGE (-6875 4450);
DISPLAY INVISIBLE (-6875 4450);
FORCEADD SCONN288_H44441003..1
(-5225 2700);
FORCEPROP 1 LAST LOCATION J9U1
J 0
(-5675 4600);
DISPLAY 0.617021 (-5675 4600);
PAINT AQUA (-5675 4600);
FORCEPROP 1 LAST PART_NUMBER H44441-003
J 0
(-5675 700);
DISPLAY 0.617021 (-5675 700);
PAINT BLUE (-5675 700);
FORCEPROP 1 LAST MATERIAL SCONN
J 0
(-5675 4550);
DISPLAY 0.617021 (-5675 4550);
PAINT SKYBLUE (-5675 4550);
FORCEPROP 2 LASTPIN (-5725 1200) $PN 146
J 2
(-5735 1210);
DISPLAY 0.617021 (-5735 1210);
PAINT ORANGE (-5735 1210);
FORCEPROP 2 LASTPIN (-5725 1550) $PN 284
J 2
(-5735 1560);
DISPLAY 0.617021 (-5735 1560);
PAINT ORANGE (-5735 1560);
FORCEPROP 2 LASTPIN (-5725 1350) $PN 285
J 2
(-5735 1360);
DISPLAY 0.617021 (-5735 1360);
PAINT ORANGE (-5735 1360);
FORCEPROP 2 LASTPIN (-5725 1300) $PN 141
J 2
(-5735 1310);
DISPLAY 0.617021 (-5735 1310);
PAINT ORANGE (-5735 1310);
FORCEPROP 2 LASTPIN (-5725 900) $PN 230
J 2
(-5735 910);
DISPLAY 0.617021 (-5735 910);
PAINT ORANGE (-5735 910);
FORCEPROP 2 LASTPIN (-5725 1500) $PN 238
J 2
(-5735 1510);
DISPLAY 0.617021 (-5735 1510);
PAINT ORANGE (-5735 1510);
FORCEPROP 2 LASTPIN (-5725 1450) $PN 140
J 2
(-5735 1460);
DISPLAY 0.617021 (-5735 1460);
PAINT ORANGE (-5735 1460);
FORCEPROP 2 LASTPIN (-5725 1400) $PN 139
J 2
(-5735 1410);
DISPLAY 0.617021 (-5735 1410);
PAINT ORANGE (-5735 1410);
FORCEPROP 2 LASTPIN (-5725 2850) $PN 237
J 2
(-5735 2860);
DISPLAY 0.617021 (-5735 2860);
PAINT ORANGE (-5735 2860);
FORCEPROP 2 LASTPIN (-5725 2800) $PN 93
J 2
(-5735 2810);
DISPLAY 0.617021 (-5735 2810);
PAINT ORANGE (-5735 2810);
FORCEPROP 2 LASTPIN (-5725 2750) $PN 89
J 2
(-5735 2760);
DISPLAY 0.617021 (-5735 2760);
PAINT ORANGE (-5735 2760);
FORCEPROP 2 LASTPIN (-5725 2700) $PN 84
J 2
(-5735 2710);
DISPLAY 0.617021 (-5735 2710);
PAINT ORANGE (-5735 2710);
FORCEPROP 2 LASTPIN (-5725 1100) $PN 144
J 2
(-5735 1110);
DISPLAY 0.617021 (-5735 1110);
PAINT ORANGE (-5735 1110);
FORCEPROP 2 LASTPIN (-5725 1050) $PN 227
J 2
(-5735 1060);
DISPLAY 0.617021 (-5735 1060);
PAINT ORANGE (-5735 1060);
FORCEPROP 2 LASTPIN (-5725 1000) $PN 205
J 2
(-5735 1010);
DISPLAY 0.617021 (-5735 1010);
PAINT ORANGE (-5735 1010);
FORCEPROP 2 LASTPIN (-5725 1800) $PN 58
J 2
(-5735 1810);
DISPLAY 0.617021 (-5735 1810);
PAINT ORANGE (-5735 1810);
FORCEPROP 2 LASTPIN (-5725 1850) $PN 222
J 2
(-5735 1860);
DISPLAY 0.617021 (-5735 1860);
PAINT ORANGE (-5735 1860);
FORCEPROP 2 LASTPIN (-5725 2450) $PN 91
J 2
(-5735 2460);
DISPLAY 0.617021 (-5735 2460);
PAINT ORANGE (-5735 2460);
FORCEPROP 2 LASTPIN (-5725 2400) $PN 87
J 2
(-5735 2410);
DISPLAY 0.617021 (-5735 2410);
PAINT ORANGE (-5735 2410);
FORCEPROP 2 LASTPIN (-5725 1750) $PN 78
J 2
(-5735 1760);
DISPLAY 0.617021 (-5735 1760);
PAINT ORANGE (-5735 1760);
FORCEPROP 2 LASTPIN (-4725 4350) $PN 280
J 0
(-4715 4360);
DISPLAY 0.617021 (-4715 4360);
PAINT ORANGE (-4715 4360);
FORCEPROP 2 LASTPIN (-4725 4300) $PN 135
J 0
(-4715 4310);
DISPLAY 0.617021 (-4715 4310);
PAINT ORANGE (-4715 4310);
FORCEPROP 2 LASTPIN (-4725 4250) $PN 273
J 0
(-4715 4260);
DISPLAY 0.617021 (-4715 4260);
PAINT ORANGE (-4715 4260);
FORCEPROP 2 LASTPIN (-4725 4200) $PN 128
J 0
(-4715 4210);
DISPLAY 0.617021 (-4715 4210);
PAINT ORANGE (-4715 4210);
FORCEPROP 2 LASTPIN (-4725 4150) $PN 282
J 0
(-4715 4160);
DISPLAY 0.617021 (-4715 4160);
PAINT ORANGE (-4715 4160);
FORCEPROP 2 LASTPIN (-4725 4100) $PN 137
J 0
(-4715 4110);
DISPLAY 0.617021 (-4715 4110);
PAINT ORANGE (-4715 4110);
FORCEPROP 2 LASTPIN (-4725 4050) $PN 275
J 0
(-4715 4060);
DISPLAY 0.617021 (-4715 4060);
PAINT ORANGE (-4715 4060);
FORCEPROP 2 LASTPIN (-4725 4000) $PN 130
J 0
(-4715 4010);
DISPLAY 0.617021 (-4715 4010);
PAINT ORANGE (-4715 4010);
FORCEPROP 2 LASTPIN (-4725 3950) $PN 269
J 0
(-4715 3960);
DISPLAY 0.617021 (-4715 3960);
PAINT ORANGE (-4715 3960);
FORCEPROP 2 LASTPIN (-4725 3900) $PN 124
J 0
(-4715 3910);
DISPLAY 0.617021 (-4715 3910);
PAINT ORANGE (-4715 3910);
FORCEPROP 2 LASTPIN (-4725 3850) $PN 262
J 0
(-4715 3860);
DISPLAY 0.617021 (-4715 3860);
PAINT ORANGE (-4715 3860);
FORCEPROP 2 LASTPIN (-4725 3800) $PN 117
J 0
(-4715 3810);
DISPLAY 0.617021 (-4715 3810);
PAINT ORANGE (-4715 3810);
FORCEPROP 2 LASTPIN (-4725 3750) $PN 271
J 0
(-4715 3760);
DISPLAY 0.617021 (-4715 3760);
PAINT ORANGE (-4715 3760);
FORCEPROP 2 LASTPIN (-4725 3700) $PN 126
J 0
(-4715 3710);
DISPLAY 0.617021 (-4715 3710);
PAINT ORANGE (-4715 3710);
FORCEPROP 2 LASTPIN (-4725 3650) $PN 264
J 0
(-4715 3660);
DISPLAY 0.617021 (-4715 3660);
PAINT ORANGE (-4715 3660);
FORCEPROP 2 LASTPIN (-4725 3600) $PN 119
J 0
(-4715 3610);
DISPLAY 0.617021 (-4715 3610);
PAINT ORANGE (-4715 3610);
FORCEPROP 2 LASTPIN (-4725 3550) $PN 258
J 0
(-4715 3560);
DISPLAY 0.617021 (-4715 3560);
PAINT ORANGE (-4715 3560);
FORCEPROP 2 LASTPIN (-4725 3500) $PN 113
J 0
(-4715 3510);
DISPLAY 0.617021 (-4715 3510);
PAINT ORANGE (-4715 3510);
FORCEPROP 2 LASTPIN (-4725 3450) $PN 251
J 0
(-4715 3460);
DISPLAY 0.617021 (-4715 3460);
PAINT ORANGE (-4715 3460);
FORCEPROP 2 LASTPIN (-4725 3400) $PN 106
J 0
(-4715 3410);
DISPLAY 0.617021 (-4715 3410);
PAINT ORANGE (-4715 3410);
FORCEPROP 2 LASTPIN (-4725 3350) $PN 260
J 0
(-4715 3360);
DISPLAY 0.617021 (-4715 3360);
PAINT ORANGE (-4715 3360);
FORCEPROP 2 LASTPIN (-4725 3300) $PN 115
J 0
(-4715 3310);
DISPLAY 0.617021 (-4715 3310);
PAINT ORANGE (-4715 3310);
FORCEPROP 2 LASTPIN (-4725 3250) $PN 253
J 0
(-4715 3260);
DISPLAY 0.617021 (-4715 3260);
PAINT ORANGE (-4715 3260);
FORCEPROP 2 LASTPIN (-4725 3200) $PN 108
J 0
(-4715 3210);
DISPLAY 0.617021 (-4715 3210);
PAINT ORANGE (-4715 3210);
FORCEPROP 2 LASTPIN (-4725 3150) $PN 247
J 0
(-4715 3160);
DISPLAY 0.617021 (-4715 3160);
PAINT ORANGE (-4715 3160);
FORCEPROP 2 LASTPIN (-4725 3100) $PN 102
J 0
(-4715 3110);
DISPLAY 0.617021 (-4715 3110);
PAINT ORANGE (-4715 3110);
FORCEPROP 2 LASTPIN (-4725 3050) $PN 240
J 0
(-4715 3060);
DISPLAY 0.617021 (-4715 3060);
PAINT ORANGE (-4715 3060);
FORCEPROP 2 LASTPIN (-4725 3000) $PN 95
J 0
(-4715 3010);
DISPLAY 0.617021 (-4715 3010);
PAINT ORANGE (-4715 3010);
FORCEPROP 2 LASTPIN (-4725 2950) $PN 249
J 0
(-4715 2960);
DISPLAY 0.617021 (-4715 2960);
PAINT ORANGE (-4715 2960);
FORCEPROP 2 LASTPIN (-4725 2900) $PN 104
J 0
(-4715 2910);
DISPLAY 0.617021 (-4715 2910);
PAINT ORANGE (-4715 2910);
FORCEPROP 2 LASTPIN (-4725 2850) $PN 242
J 0
(-4715 2860);
DISPLAY 0.617021 (-4715 2860);
PAINT ORANGE (-4715 2860);
FORCEPROP 2 LASTPIN (-4725 2800) $PN 97
J 0
(-4715 2810);
DISPLAY 0.617021 (-4715 2810);
PAINT ORANGE (-4715 2810);
FORCEPROP 2 LASTPIN (-4725 2750) $PN 188
J 0
(-4715 2760);
DISPLAY 0.617021 (-4715 2760);
PAINT ORANGE (-4715 2760);
FORCEPROP 2 LASTPIN (-4725 2700) $PN 43
J 0
(-4715 2710);
DISPLAY 0.617021 (-4715 2710);
PAINT ORANGE (-4715 2710);
FORCEPROP 2 LASTPIN (-4725 2650) $PN 181
J 0
(-4715 2660);
DISPLAY 0.617021 (-4715 2660);
PAINT ORANGE (-4715 2660);
FORCEPROP 2 LASTPIN (-4725 2600) $PN 36
J 0
(-4715 2610);
DISPLAY 0.617021 (-4715 2610);
PAINT ORANGE (-4715 2610);
FORCEPROP 2 LASTPIN (-4725 2550) $PN 190
J 0
(-4715 2560);
DISPLAY 0.617021 (-4715 2560);
PAINT ORANGE (-4715 2560);
FORCEPROP 2 LASTPIN (-4725 2500) $PN 45
J 0
(-4715 2510);
DISPLAY 0.617021 (-4715 2510);
PAINT ORANGE (-4715 2510);
FORCEPROP 2 LASTPIN (-4725 2450) $PN 183
J 0
(-4715 2460);
DISPLAY 0.617021 (-4715 2460);
PAINT ORANGE (-4715 2460);
FORCEPROP 2 LASTPIN (-4725 2400) $PN 38
J 0
(-4715 2410);
DISPLAY 0.617021 (-4715 2410);
PAINT ORANGE (-4715 2410);
FORCEPROP 2 LASTPIN (-4725 2350) $PN 177
J 0
(-4715 2360);
DISPLAY 0.617021 (-4715 2360);
PAINT ORANGE (-4715 2360);
FORCEPROP 2 LASTPIN (-4725 2300) $PN 32
J 0
(-4715 2310);
DISPLAY 0.617021 (-4715 2310);
PAINT ORANGE (-4715 2310);
FORCEPROP 2 LASTPIN (-4725 2250) $PN 170
J 0
(-4715 2260);
DISPLAY 0.617021 (-4715 2260);
PAINT ORANGE (-4715 2260);
FORCEPROP 2 LASTPIN (-4725 2200) $PN 25
J 0
(-4715 2210);
DISPLAY 0.617021 (-4715 2210);
PAINT ORANGE (-4715 2210);
FORCEPROP 2 LASTPIN (-4725 2150) $PN 179
J 0
(-4715 2160);
DISPLAY 0.617021 (-4715 2160);
PAINT ORANGE (-4715 2160);
FORCEPROP 2 LASTPIN (-4725 2100) $PN 34
J 0
(-4715 2110);
DISPLAY 0.617021 (-4715 2110);
PAINT ORANGE (-4715 2110);
FORCEPROP 2 LASTPIN (-4725 2050) $PN 172
J 0
(-4715 2060);
DISPLAY 0.617021 (-4715 2060);
PAINT ORANGE (-4715 2060);
FORCEPROP 2 LASTPIN (-4725 2000) $PN 27
J 0
(-4715 2010);
DISPLAY 0.617021 (-4715 2010);
PAINT ORANGE (-4715 2010);
FORCEPROP 2 LASTPIN (-4725 1950) $PN 166
J 0
(-4715 1960);
DISPLAY 0.617021 (-4715 1960);
PAINT ORANGE (-4715 1960);
FORCEPROP 2 LASTPIN (-4725 1900) $PN 21
J 0
(-4715 1910);
DISPLAY 0.617021 (-4715 1910);
PAINT ORANGE (-4715 1910);
FORCEPROP 2 LASTPIN (-4725 1850) $PN 159
J 0
(-4715 1860);
DISPLAY 0.617021 (-4715 1860);
PAINT ORANGE (-4715 1860);
FORCEPROP 2 LASTPIN (-4725 1800) $PN 14
J 0
(-4715 1810);
DISPLAY 0.617021 (-4715 1810);
PAINT ORANGE (-4715 1810);
FORCEPROP 2 LASTPIN (-4725 1750) $PN 168
J 0
(-4715 1760);
DISPLAY 0.617021 (-4715 1760);
PAINT ORANGE (-4715 1760);
FORCEPROP 2 LASTPIN (-4725 1700) $PN 23
J 0
(-4715 1710);
DISPLAY 0.617021 (-4715 1710);
PAINT ORANGE (-4715 1710);
FORCEPROP 2 LASTPIN (-4725 1650) $PN 161
J 0
(-4715 1660);
DISPLAY 0.617021 (-4715 1660);
PAINT ORANGE (-4715 1660);
FORCEPROP 2 LASTPIN (-4725 1600) $PN 16
J 0
(-4715 1610);
DISPLAY 0.617021 (-4715 1610);
PAINT ORANGE (-4715 1610);
FORCEPROP 2 LASTPIN (-4725 1550) $PN 155
J 0
(-4715 1560);
DISPLAY 0.617021 (-4715 1560);
PAINT ORANGE (-4715 1560);
FORCEPROP 2 LASTPIN (-4725 1500) $PN 10
J 0
(-4715 1510);
DISPLAY 0.617021 (-4715 1510);
PAINT ORANGE (-4715 1510);
FORCEPROP 2 LASTPIN (-4725 1450) $PN 148
J 0
(-4715 1460);
DISPLAY 0.617021 (-4715 1460);
PAINT ORANGE (-4715 1460);
FORCEPROP 2 LASTPIN (-4725 1400) $PN 3
J 0
(-4715 1410);
DISPLAY 0.617021 (-4715 1410);
PAINT ORANGE (-4715 1410);
FORCEPROP 2 LASTPIN (-4725 1350) $PN 157
J 0
(-4715 1360);
DISPLAY 0.617021 (-4715 1360);
PAINT ORANGE (-4715 1360);
FORCEPROP 2 LASTPIN (-4725 1300) $PN 12
J 0
(-4715 1310);
DISPLAY 0.617021 (-4715 1310);
PAINT ORANGE (-4715 1310);
FORCEPROP 2 LASTPIN (-4725 1250) $PN 150
J 0
(-4715 1260);
DISPLAY 0.617021 (-4715 1260);
PAINT ORANGE (-4715 1260);
FORCEPROP 2 LASTPIN (-4725 1200) $PN 5
J 0
(-4715 1210);
DISPLAY 0.617021 (-4715 1210);
PAINT ORANGE (-4715 1210);
FORCEPROP 2 LASTPIN (-5725 2600) $PN 203
J 2
(-5735 2610);
DISPLAY 0.617021 (-5735 2610);
PAINT ORANGE (-5735 2610);
FORCEPROP 2 LASTPIN (-5725 2550) $PN 60
J 2
(-5735 2560);
DISPLAY 0.617021 (-5735 2560);
PAINT ORANGE (-5735 2560);
FORCEPROP 2 LASTPIN (-5725 3150) $PN 218
J 2
(-5735 3160);
DISPLAY 0.617021 (-5735 3160);
PAINT ORANGE (-5735 3160);
FORCEPROP 2 LASTPIN (-5725 3100) $PN 219
J 2
(-5735 3110);
DISPLAY 0.617021 (-5735 3110);
PAINT ORANGE (-5735 3110);
FORCEPROP 2 LASTPIN (-5725 3050) $PN 74
J 2
(-5735 3060);
DISPLAY 0.617021 (-5735 3060);
PAINT ORANGE (-5735 3060);
FORCEPROP 2 LASTPIN (-5725 3000) $PN 75
J 2
(-5735 3010);
DISPLAY 0.617021 (-5735 3010);
PAINT ORANGE (-5735 3010);
FORCEPROP 2 LASTPIN (-5725 2300) $PN 199
J 2
(-5735 2310);
DISPLAY 0.617021 (-5735 2310);
PAINT ORANGE (-5735 2310);
FORCEPROP 2 LASTPIN (-5725 2250) $PN 54
J 2
(-5735 2260);
DISPLAY 0.617021 (-5735 2260);
PAINT ORANGE (-5735 2260);
FORCEPROP 2 LASTPIN (-5725 2200) $PN 192
J 2
(-5735 2210);
DISPLAY 0.617021 (-5735 2210);
PAINT ORANGE (-5735 2210);
FORCEPROP 2 LASTPIN (-5725 2150) $PN 47
J 2
(-5735 2160);
DISPLAY 0.617021 (-5735 2160);
PAINT ORANGE (-5735 2160);
FORCEPROP 2 LASTPIN (-5725 2100) $PN 201
J 2
(-5735 2110);
DISPLAY 0.617021 (-5735 2110);
PAINT ORANGE (-5735 2110);
FORCEPROP 2 LASTPIN (-5725 2050) $PN 56
J 2
(-5735 2060);
DISPLAY 0.617021 (-5735 2060);
PAINT ORANGE (-5735 2060);
FORCEPROP 2 LASTPIN (-5725 2000) $PN 194
J 2
(-5735 2010);
DISPLAY 0.617021 (-5735 2010);
PAINT ORANGE (-5735 2010);
FORCEPROP 2 LASTPIN (-5725 1950) $PN 49
J 2
(-5735 1960);
DISPLAY 0.617021 (-5735 1960);
PAINT ORANGE (-5735 1960);
FORCEPROP 2 LASTPIN (-5725 2900) $PN 235
J 2
(-5735 2910);
DISPLAY 0.617021 (-5735 2910);
PAINT ORANGE (-5735 2910);
FORCEPROP 2 LASTPIN (-5725 3300) $PN 207
J 2
(-5735 3310);
DISPLAY 0.617021 (-5735 3310);
PAINT ORANGE (-5735 3310);
FORCEPROP 2 LASTPIN (-5725 3250) $PN 63
J 2
(-5735 3260);
DISPLAY 0.617021 (-5735 3260);
PAINT ORANGE (-5735 3260);
FORCEPROP 2 LASTPIN (-5725 3400) $PN 224
J 2
(-5735 3410);
DISPLAY 0.617021 (-5735 3410);
PAINT ORANGE (-5735 3410);
FORCEPROP 2 LASTPIN (-5725 3350) $PN 81
J 2
(-5735 3360);
DISPLAY 0.617021 (-5735 3360);
PAINT ORANGE (-5735 3360);
FORCEPROP 2 LASTPIN (-5725 1700) $PN 208
J 2
(-5735 1710);
DISPLAY 0.617021 (-5735 1710);
PAINT ORANGE (-5735 1710);
FORCEPROP 2 LASTPIN (-5725 1650) $PN 62
J 2
(-5735 1660);
DISPLAY 0.617021 (-5735 1660);
PAINT ORANGE (-5735 1660);
FORCEPROP 2 LASTPIN (-5725 4350) $PN 234
J 2
(-5735 4360);
DISPLAY 0.617021 (-5735 4360);
PAINT ORANGE (-5735 4360);
FORCEPROP 2 LASTPIN (-5725 4300) $PN 82
J 2
(-5735 4310);
DISPLAY 0.617021 (-5735 4310);
PAINT ORANGE (-5735 4310);
FORCEPROP 2 LASTPIN (-5725 4250) $PN 86
J 2
(-5735 4260);
DISPLAY 0.617021 (-5735 4260);
PAINT ORANGE (-5735 4260);
FORCEPROP 2 LASTPIN (-5725 4200) $PN 228
J 2
(-5735 4210);
DISPLAY 0.617021 (-5735 4210);
PAINT ORANGE (-5735 4210);
FORCEPROP 2 LASTPIN (-5725 4150) $PN 232
J 2
(-5735 4160);
DISPLAY 0.617021 (-5735 4160);
PAINT ORANGE (-5735 4160);
FORCEPROP 2 LASTPIN (-5725 4100) $PN 65
J 2
(-5735 4110);
DISPLAY 0.617021 (-5735 4110);
PAINT ORANGE (-5735 4110);
FORCEPROP 2 LASTPIN (-5725 4050) $PN 210
J 2
(-5735 4060);
DISPLAY 0.617021 (-5735 4060);
PAINT ORANGE (-5735 4060);
FORCEPROP 2 LASTPIN (-5725 4000) $PN 225
J 2
(-5735 4010);
DISPLAY 0.617021 (-5735 4010);
PAINT ORANGE (-5735 4010);
FORCEPROP 2 LASTPIN (-5725 3950) $PN 66
J 2
(-5735 3960);
DISPLAY 0.617021 (-5735 3960);
PAINT ORANGE (-5735 3960);
FORCEPROP 2 LASTPIN (-5725 3900) $PN 68
J 2
(-5735 3910);
DISPLAY 0.617021 (-5735 3910);
PAINT ORANGE (-5735 3910);
FORCEPROP 2 LASTPIN (-5725 3850) $PN 211
J 2
(-5735 3860);
DISPLAY 0.617021 (-5735 3860);
PAINT ORANGE (-5735 3860);
FORCEPROP 2 LASTPIN (-5725 3800) $PN 69
J 2
(-5735 3810);
DISPLAY 0.617021 (-5735 3810);
PAINT ORANGE (-5735 3810);
FORCEPROP 2 LASTPIN (-5725 3750) $PN 213
J 2
(-5735 3760);
DISPLAY 0.617021 (-5735 3760);
PAINT ORANGE (-5735 3760);
FORCEPROP 2 LASTPIN (-5725 3700) $PN 214
J 2
(-5735 3710);
DISPLAY 0.617021 (-5735 3710);
PAINT ORANGE (-5735 3710);
FORCEPROP 2 LASTPIN (-5725 3650) $PN 71
J 2
(-5735 3660);
DISPLAY 0.617021 (-5735 3660);
PAINT ORANGE (-5735 3660);
FORCEPROP 2 LASTPIN (-5725 3600) $PN 216
J 2
(-5735 3610);
DISPLAY 0.617021 (-5735 3610);
PAINT ORANGE (-5735 3610);
FORCEPROP 2 LASTPIN (-5725 3550) $PN 72
J 2
(-5735 3560);
DISPLAY 0.617021 (-5735 3560);
PAINT ORANGE (-5735 3560);
FORCEPROP 2 LASTPIN (-5725 3500) $PN 79
J 2
(-5735 3510);
DISPLAY 0.617021 (-5735 3510);
PAINT ORANGE (-5735 3510);
FORCEPROP 1 LAST PACK_TYPE PIP
J 0
(-5675 4650);
PAINT SKYBLUE (-5675 4650);
DISPLAY INVISIBLE (-5675 4650);
FORCEPROP 2 LAST BOM_COST MEM
J 0
(-5225 2700);
PAINT ORANGE (-5225 2700);
DISPLAY INVISIBLE (-5225 2700);
FORCEPROP 2 LAST CDS_LIB mstr_sconn
J 0
(-5225 2700);
PAINT ORANGE (-5225 2700);
DISPLAY INVISIBLE (-5225 2700);
FORCEPROP 2 LAST SEC_TYPE PIP
J 0
(-5675 4650);
DISPLAY 1.021277 (-5675 4650);
PAINT ORANGE (-5675 4650);
DISPLAY INVISIBLE (-5675 4650);
FORCEPROP 2 LAST SEC 1
J 0
(-5675 4650);
DISPLAY 0.680851 (-5675 4650);
PAINT MONO (-5675 4650);
DISPLAY INVISIBLE (-5675 4650);
FORCEPROP 2 LAST CDS_LOCATION J9U1
J 0
(-5675 4600);
DISPLAY 0.617021 (-5675 4600);
PAINT AQUA (-5675 4600);
DISPLAY INVISIBLE (-5675 4600);
FORCEPROP 1 LAST PATH I24
J 0
(-5225 4550);
PAINT GREEN (-5225 4550);
DISPLAY INVISIBLE (-5225 4550);
FORCEPROP 2 LAST ROOM DDR4_GH_H
J 0
(-5225 2700);
PAINT ORANGE (-5225 2700);
DISPLAY INVISIBLE (-5225 2700);
FORCEADD TAP..6
(-5975 1950);
FORCEPROP 3 LASTPIN (-5925 1950) SIG_NAME M_H_ECC<0>
J 0
(-5915 1960);
DISPLAY 0.659574 (-5915 1960);
PAINT MONO (-5915 1960);
DISPLAY INVISIBLE (-5915 1960);
FORCEPROP 1 LASTPIN (-5925 1950) BN 0
J 0
(-5975 1960);
DISPLAY 0.617021 (-5975 1960);
PAINT PINK (-5975 1960);
FORCEPROP 2 LAST CDS_LIB mstr_standard
J 0
(-5975 1950);
DISPLAY 0.787234 (-5975 1950);
PAINT MONO (-5975 1950);
DISPLAY INVISIBLE (-5975 1950);
FORCEPROP 1 LAST BODY_TYPE PLUMBING
J 0
(-5975 1900);
DISPLAY 1.234043 (-5975 1900);
PAINT GREEN (-5975 1900);
DISPLAY INVISIBLE (-5975 1900);
FORCEPROP 1 LAST HDL_TAP TRUE
J 0
(-5650 1825);
DISPLAY 1.234043 (-5650 1825);
PAINT GREEN (-5650 1825);
DISPLAY INVISIBLE (-5650 1825);
FORCEPROP 1 LAST PATH I25
J 0
(-5977 1950);
DISPLAY 0.872340 (-5977 1950);
PAINT GREEN (-5977 1950);
DISPLAY INVISIBLE (-5977 1950);
FORCEADD TAP..6
(-5975 2000);
FORCEPROP 3 LASTPIN (-5925 2000) SIG_NAME M_H_ECC<1>
J 0
(-5915 2010);
DISPLAY 0.659574 (-5915 2010);
PAINT MONO (-5915 2010);
DISPLAY INVISIBLE (-5915 2010);
FORCEPROP 1 LASTPIN (-5925 2000) BN 1
J 0
(-5975 2010);
DISPLAY 0.617021 (-5975 2010);
PAINT PINK (-5975 2010);
FORCEPROP 2 LAST CDS_LIB mstr_standard
J 0
(-5975 2000);
DISPLAY 0.787234 (-5975 2000);
PAINT MONO (-5975 2000);
DISPLAY INVISIBLE (-5975 2000);
FORCEPROP 1 LAST BODY_TYPE PLUMBING
J 0
(-5975 1950);
DISPLAY 1.234043 (-5975 1950);
PAINT GREEN (-5975 1950);
DISPLAY INVISIBLE (-5975 1950);
FORCEPROP 1 LAST HDL_TAP TRUE
J 0
(-5650 1875);
DISPLAY 1.234043 (-5650 1875);
PAINT GREEN (-5650 1875);
DISPLAY INVISIBLE (-5650 1875);
FORCEPROP 1 LAST PATH I26
J 0
(-5977 2000);
DISPLAY 0.872340 (-5977 2000);
PAINT GREEN (-5977 2000);
DISPLAY INVISIBLE (-5977 2000);
FORCEADD TAP..6
(-5975 2100);
FORCEPROP 3 LASTPIN (-5925 2100) SIG_NAME M_H_ECC<3>
J 0
(-5915 2110);
DISPLAY 0.659574 (-5915 2110);
PAINT MONO (-5915 2110);
DISPLAY INVISIBLE (-5915 2110);
FORCEPROP 1 LASTPIN (-5925 2100) BN 3
J 0
(-5975 2110);
DISPLAY 0.617021 (-5975 2110);
PAINT PINK (-5975 2110);
FORCEPROP 2 LAST CDS_LIB mstr_standard
J 0
(-5975 2100);
DISPLAY 0.787234 (-5975 2100);
PAINT MONO (-5975 2100);
DISPLAY INVISIBLE (-5975 2100);
FORCEPROP 1 LAST BODY_TYPE PLUMBING
J 0
(-5975 2050);
DISPLAY 1.234043 (-5975 2050);
PAINT GREEN (-5975 2050);
DISPLAY INVISIBLE (-5975 2050);
FORCEPROP 1 LAST HDL_TAP TRUE
J 0
(-5650 1975);
DISPLAY 1.234043 (-5650 1975);
PAINT GREEN (-5650 1975);
DISPLAY INVISIBLE (-5650 1975);
FORCEPROP 1 LAST PATH I27
J 0
(-5977 2100);
DISPLAY 0.872340 (-5977 2100);
PAINT GREEN (-5977 2100);
DISPLAY INVISIBLE (-5977 2100);
FORCEADD TAP..6
(-5975 2050);
FORCEPROP 3 LASTPIN (-5925 2050) SIG_NAME M_H_ECC<2>
J 0
(-5915 2060);
DISPLAY 0.659574 (-5915 2060);
PAINT MONO (-5915 2060);
DISPLAY INVISIBLE (-5915 2060);
FORCEPROP 1 LASTPIN (-5925 2050) BN 2
J 0
(-5975 2060);
DISPLAY 0.617021 (-5975 2060);
PAINT PINK (-5975 2060);
FORCEPROP 2 LAST CDS_LIB mstr_standard
J 0
(-5975 2050);
DISPLAY 0.787234 (-5975 2050);
PAINT MONO (-5975 2050);
DISPLAY INVISIBLE (-5975 2050);
FORCEPROP 1 LAST BODY_TYPE PLUMBING
J 0
(-5975 2000);
DISPLAY 1.234043 (-5975 2000);
PAINT GREEN (-5975 2000);
DISPLAY INVISIBLE (-5975 2000);
FORCEPROP 1 LAST HDL_TAP TRUE
J 0
(-5650 1925);
DISPLAY 1.234043 (-5650 1925);
PAINT GREEN (-5650 1925);
DISPLAY INVISIBLE (-5650 1925);
FORCEPROP 1 LAST PATH I28
J 0
(-5977 2050);
DISPLAY 0.872340 (-5977 2050);
PAINT GREEN (-5977 2050);
DISPLAY INVISIBLE (-5977 2050);
FORCEADD TAP..6
(-5975 2200);
FORCEPROP 3 LASTPIN (-5925 2200) SIG_NAME M_H_ECC<5>
J 0
(-5915 2210);
DISPLAY 0.659574 (-5915 2210);
PAINT MONO (-5915 2210);
DISPLAY INVISIBLE (-5915 2210);
FORCEPROP 1 LASTPIN (-5925 2200) BN 5
J 0
(-5975 2210);
DISPLAY 0.617021 (-5975 2210);
PAINT PINK (-5975 2210);
FORCEPROP 2 LAST CDS_LIB mstr_standard
J 0
(-5975 2200);
DISPLAY 0.787234 (-5975 2200);
PAINT MONO (-5975 2200);
DISPLAY INVISIBLE (-5975 2200);
FORCEPROP 1 LAST BODY_TYPE PLUMBING
J 0
(-5975 2150);
DISPLAY 1.234043 (-5975 2150);
PAINT GREEN (-5975 2150);
DISPLAY INVISIBLE (-5975 2150);
FORCEPROP 1 LAST HDL_TAP TRUE
J 0
(-5650 2075);
DISPLAY 1.234043 (-5650 2075);
PAINT GREEN (-5650 2075);
DISPLAY INVISIBLE (-5650 2075);
FORCEPROP 1 LAST PATH I29
J 0
(-5977 2200);
DISPLAY 0.872340 (-5977 2200);
PAINT GREEN (-5977 2200);
DISPLAY INVISIBLE (-5977 2200);
FORCEADD CAP_A..1
R 2
(-7225 1000);
FORCEPROP 1 LAST LOCATION C1G10
J 2
(-7275 1100);
DISPLAY 0.617021 (-7275 1100);
PAINT AQUA (-7275 1100);
FORCEPROP 1 LAST PART_NUMBER A36096-045
J 2
(-7275 850);
DISPLAY 0.617021 (-7275 850);
PAINT BLUE (-7275 850);
FORCEPROP 1 LAST VALUE 0.01UF
J 2
(-7275 1050);
DISPLAY 0.617021 (-7275 1050);
PAINT SKYBLUE (-7275 1050);
FORCEPROP 1 LAST TOLERANCE 10%
J 2
(-7275 950);
DISPLAY 0.617021 (-7275 950);
PAINT SKYBLUE (-7275 950);
FORCEPROP 1 LAST PACK_TYPE 0402V
J 2
(-7275 800);
DISPLAY 0.617021 (-7275 800);
PAINT SKYBLUE (-7275 800);
FORCEPROP 1 LAST VOLTAGE 25V
J 2
(-7275 1000);
DISPLAY 0.617021 (-7275 1000);
PAINT SKYBLUE (-7275 1000);
FORCEPROP 1 LAST MATERIAL X7R
J 2
(-7275 900);
DISPLAY 0.617021 (-7275 900);
PAINT SKYBLUE (-7275 900);
FORCEPROP 2 LAST CDS_LOCATION C1G10
J 2
(-7275 1100);
DISPLAY 0.617021 (-7275 1100);
PAINT AQUA (-7275 1100);
DISPLAY INVISIBLE (-7275 1100);
FORCEPROP 2 LAST BOM_COST MEM
J 0
(-7225 1000);
PAINT ORANGE (-7225 1000);
DISPLAY INVISIBLE (-7225 1000);
FORCEPROP 2 LAST CDS_LIB dev_discrete
J 0
(-7225 1000);
PAINT ORANGE (-7225 1000);
DISPLAY INVISIBLE (-7225 1000);
FORCEPROP 2 LAST CDS_SEC 1
J 0
(-7275 1200);
PAINT MONO (-7275 1200);
DISPLAY INVISIBLE (-7275 1200);
FORCEPROP 2 LAST $SEC 1
J 0
(-7275 1200);
PAINT MONO (-7275 1200);
DISPLAY INVISIBLE (-7275 1200);
FORCEPROP 1 LAST PATH I3
J 2
(-7275 1150);
DISPLAY 0.978723 (-7275 1150);
PAINT WHITE (-7275 1150);
DISPLAY INVISIBLE (-7275 1150);
FORCEPROP 2 LAST ROOM DDR4_GH_G
J 0
(-7225 1000);
PAINT ORANGE (-7225 1000);
DISPLAY INVISIBLE (-7225 1000);
FORCEPROP 1 LASTPIN (-7225 1100) $PN 1
J 2
(-7235 1080);
DISPLAY 0.787234 (-7235 1080);
PAINT ORANGE (-7235 1080);
DISPLAY INVISIBLE (-7235 1080);
FORCEPROP 1 LASTPIN (-7225 900) $PN 2
J 2
(-7235 880);
DISPLAY 0.787234 (-7235 880);
PAINT ORANGE (-7235 880);
DISPLAY INVISIBLE (-7235 880);
FORCEADD TAP..6
(-5975 2150);
FORCEPROP 3 LASTPIN (-5925 2150) SIG_NAME M_H_ECC<4>
J 0
(-5915 2160);
DISPLAY 0.659574 (-5915 2160);
PAINT MONO (-5915 2160);
DISPLAY INVISIBLE (-5915 2160);
FORCEPROP 1 LASTPIN (-5925 2150) BN 4
J 0
(-5975 2160);
DISPLAY 0.617021 (-5975 2160);
PAINT PINK (-5975 2160);
FORCEPROP 2 LAST CDS_LIB mstr_standard
J 0
(-5975 2150);
DISPLAY 0.787234 (-5975 2150);
PAINT MONO (-5975 2150);
DISPLAY INVISIBLE (-5975 2150);
FORCEPROP 1 LAST BODY_TYPE PLUMBING
J 0
(-5975 2100);
DISPLAY 1.234043 (-5975 2100);
PAINT GREEN (-5975 2100);
DISPLAY INVISIBLE (-5975 2100);
FORCEPROP 1 LAST HDL_TAP TRUE
J 0
(-5650 2025);
DISPLAY 1.234043 (-5650 2025);
PAINT GREEN (-5650 2025);
DISPLAY INVISIBLE (-5650 2025);
FORCEPROP 1 LAST PATH I30
J 0
(-5977 2150);
DISPLAY 0.872340 (-5977 2150);
PAINT GREEN (-5977 2150);
DISPLAY INVISIBLE (-5977 2150);
FORCEADD TAP..6
(-5975 2250);
FORCEPROP 3 LASTPIN (-5925 2250) SIG_NAME M_H_ECC<6>
J 0
(-5915 2260);
DISPLAY 0.659574 (-5915 2260);
PAINT MONO (-5915 2260);
DISPLAY INVISIBLE (-5915 2260);
FORCEPROP 1 LASTPIN (-5925 2250) BN 6
J 0
(-5975 2260);
DISPLAY 0.617021 (-5975 2260);
PAINT PINK (-5975 2260);
FORCEPROP 2 LAST CDS_LIB mstr_standard
J 0
(-5975 2250);
DISPLAY 0.787234 (-5975 2250);
PAINT MONO (-5975 2250);
DISPLAY INVISIBLE (-5975 2250);
FORCEPROP 1 LAST BODY_TYPE PLUMBING
J 0
(-5975 2200);
DISPLAY 1.234043 (-5975 2200);
PAINT GREEN (-5975 2200);
DISPLAY INVISIBLE (-5975 2200);
FORCEPROP 1 LAST HDL_TAP TRUE
J 0
(-5650 2125);
DISPLAY 1.234043 (-5650 2125);
PAINT GREEN (-5650 2125);
DISPLAY INVISIBLE (-5650 2125);
FORCEPROP 1 LAST PATH I31
J 0
(-5977 2250);
DISPLAY 0.872340 (-5977 2250);
PAINT GREEN (-5977 2250);
DISPLAY INVISIBLE (-5977 2250);
FORCEADD TAP..6
(-5975 2300);
FORCEPROP 3 LASTPIN (-5925 2300) SIG_NAME M_H_ECC<7>
J 0
(-5915 2310);
DISPLAY 0.659574 (-5915 2310);
PAINT MONO (-5915 2310);
DISPLAY INVISIBLE (-5915 2310);
FORCEPROP 1 LASTPIN (-5925 2300) BN 7
J 0
(-5975 2310);
DISPLAY 0.617021 (-5975 2310);
PAINT PINK (-5975 2310);
FORCEPROP 2 LAST CDS_LIB mstr_standard
J 0
(-5975 2300);
DISPLAY 0.787234 (-5975 2300);
PAINT MONO (-5975 2300);
DISPLAY INVISIBLE (-5975 2300);
FORCEPROP 1 LAST BODY_TYPE PLUMBING
J 0
(-5975 2250);
DISPLAY 1.234043 (-5975 2250);
PAINT GREEN (-5975 2250);
DISPLAY INVISIBLE (-5975 2250);
FORCEPROP 1 LAST HDL_TAP TRUE
J 0
(-5650 2175);
DISPLAY 1.234043 (-5650 2175);
PAINT GREEN (-5650 2175);
DISPLAY INVISIBLE (-5650 2175);
FORCEPROP 1 LAST PATH I32
J 0
(-5977 2300);
DISPLAY 0.872340 (-5977 2300);
PAINT GREEN (-5977 2300);
DISPLAY INVISIBLE (-5977 2300);
FORCEADD TAP..6
(-5975 2400);
FORCEPROP 3 LASTPIN (-5925 2400) SIG_NAME M_H_ODT<2>
J 0
(-5915 2410);
DISPLAY 0.659574 (-5915 2410);
PAINT MONO (-5915 2410);
DISPLAY INVISIBLE (-5915 2410);
FORCEPROP 1 LASTPIN (-5925 2400) BN 2
J 0
(-5975 2410);
DISPLAY 0.617021 (-5975 2410);
PAINT PINK (-5975 2410);
FORCEPROP 2 LAST CDS_LIB mstr_standard
J 0
(-5975 2400);
DISPLAY 0.787234 (-5975 2400);
PAINT MONO (-5975 2400);
DISPLAY INVISIBLE (-5975 2400);
FORCEPROP 1 LAST BODY_TYPE PLUMBING
J 0
(-5975 2350);
DISPLAY 1.234043 (-5975 2350);
PAINT GREEN (-5975 2350);
DISPLAY INVISIBLE (-5975 2350);
FORCEPROP 1 LAST HDL_TAP TRUE
J 0
(-5650 2275);
DISPLAY 1.234043 (-5650 2275);
PAINT GREEN (-5650 2275);
DISPLAY INVISIBLE (-5650 2275);
FORCEPROP 1 LAST PATH I33
J 0
(-5977 2400);
DISPLAY 0.872340 (-5977 2400);
PAINT GREEN (-5977 2400);
DISPLAY INVISIBLE (-5977 2400);
FORCEADD TAP..6
(-5975 2450);
FORCEPROP 3 LASTPIN (-5925 2450) SIG_NAME M_H_ODT<3>
J 0
(-5915 2460);
DISPLAY 0.659574 (-5915 2460);
PAINT MONO (-5915 2460);
DISPLAY INVISIBLE (-5915 2460);
FORCEPROP 1 LASTPIN (-5925 2450) BN 3
J 0
(-5975 2460);
DISPLAY 0.617021 (-5975 2460);
PAINT PINK (-5975 2460);
FORCEPROP 2 LAST CDS_LIB mstr_standard
J 0
(-5975 2450);
DISPLAY 0.787234 (-5975 2450);
PAINT MONO (-5975 2450);
DISPLAY INVISIBLE (-5975 2450);
FORCEPROP 1 LAST BODY_TYPE PLUMBING
J 0
(-5975 2400);
DISPLAY 1.234043 (-5975 2400);
PAINT GREEN (-5975 2400);
DISPLAY INVISIBLE (-5975 2400);
FORCEPROP 1 LAST HDL_TAP TRUE
J 0
(-5650 2325);
DISPLAY 1.234043 (-5650 2325);
PAINT GREEN (-5650 2325);
DISPLAY INVISIBLE (-5650 2325);
FORCEPROP 1 LAST PATH I34
J 0
(-5977 2450);
DISPLAY 0.872340 (-5977 2450);
PAINT GREEN (-5977 2450);
DISPLAY INVISIBLE (-5977 2450);
FORCEADD TAP..6
(-6175 3000);
FORCEPROP 3 LASTPIN (-6125 3000) SIG_NAME M_H_CLK_DN<2>
J 0
(-6115 3010);
DISPLAY 0.659574 (-6115 3010);
PAINT MONO (-6115 3010);
DISPLAY INVISIBLE (-6115 3010);
FORCEPROP 1 LASTPIN (-6125 3000) BN 2
J 0
(-6175 3010);
DISPLAY 0.617021 (-6175 3010);
PAINT PINK (-6175 3010);
FORCEPROP 2 LAST CDS_LIB mstr_standard
J 0
(-6175 3000);
DISPLAY 0.787234 (-6175 3000);
PAINT MONO (-6175 3000);
DISPLAY INVISIBLE (-6175 3000);
FORCEPROP 1 LAST BODY_TYPE PLUMBING
J 0
(-6175 2950);
DISPLAY 1.234043 (-6175 2950);
PAINT GREEN (-6175 2950);
DISPLAY INVISIBLE (-6175 2950);
FORCEPROP 1 LAST HDL_TAP TRUE
J 0
(-5850 2875);
DISPLAY 1.234043 (-5850 2875);
PAINT GREEN (-5850 2875);
DISPLAY INVISIBLE (-5850 2875);
FORCEPROP 1 LAST PATH I35
J 0
(-6177 3000);
DISPLAY 0.872340 (-6177 3000);
PAINT GREEN (-6177 3000);
DISPLAY INVISIBLE (-6177 3000);
FORCEADD TAP..6
(-6175 3100);
FORCEPROP 3 LASTPIN (-6125 3100) SIG_NAME M_H_CLK_DN<3>
J 0
(-6115 3110);
DISPLAY 0.659574 (-6115 3110);
PAINT MONO (-6115 3110);
DISPLAY INVISIBLE (-6115 3110);
FORCEPROP 1 LASTPIN (-6125 3100) BN 3
J 0
(-6175 3110);
DISPLAY 0.617021 (-6175 3110);
PAINT PINK (-6175 3110);
FORCEPROP 2 LAST CDS_LIB mstr_standard
J 0
(-6175 3100);
DISPLAY 0.787234 (-6175 3100);
PAINT MONO (-6175 3100);
DISPLAY INVISIBLE (-6175 3100);
FORCEPROP 1 LAST BODY_TYPE PLUMBING
J 0
(-6175 3050);
DISPLAY 1.234043 (-6175 3050);
PAINT GREEN (-6175 3050);
DISPLAY INVISIBLE (-6175 3050);
FORCEPROP 1 LAST HDL_TAP TRUE
J 0
(-5850 2975);
DISPLAY 1.234043 (-5850 2975);
PAINT GREEN (-5850 2975);
DISPLAY INVISIBLE (-5850 2975);
FORCEPROP 1 LAST PATH I36
J 0
(-6177 3100);
DISPLAY 0.872340 (-6177 3100);
PAINT GREEN (-6177 3100);
DISPLAY INVISIBLE (-6177 3100);
FORCEADD TAP..6
(-5975 2600);
FORCEPROP 3 LASTPIN (-5925 2600) SIG_NAME M_H_CKE<3>
J 0
(-5915 2610);
DISPLAY 0.659574 (-5915 2610);
PAINT MONO (-5915 2610);
DISPLAY INVISIBLE (-5915 2610);
FORCEPROP 1 LASTPIN (-5925 2600) BN 3
J 0
(-5975 2610);
DISPLAY 0.617021 (-5975 2610);
PAINT PINK (-5975 2610);
FORCEPROP 2 LAST CDS_LIB mstr_standard
J 0
(-5975 2600);
DISPLAY 0.787234 (-5975 2600);
PAINT MONO (-5975 2600);
DISPLAY INVISIBLE (-5975 2600);
FORCEPROP 1 LAST BODY_TYPE PLUMBING
J 0
(-5975 2550);
DISPLAY 1.234043 (-5975 2550);
PAINT GREEN (-5975 2550);
DISPLAY INVISIBLE (-5975 2550);
FORCEPROP 1 LAST HDL_TAP TRUE
J 0
(-5650 2475);
DISPLAY 1.234043 (-5650 2475);
PAINT GREEN (-5650 2475);
DISPLAY INVISIBLE (-5650 2475);
FORCEPROP 1 LAST PATH I37
J 0
(-5977 2600);
DISPLAY 0.872340 (-5977 2600);
PAINT GREEN (-5977 2600);
DISPLAY INVISIBLE (-5977 2600);
FORCEADD TAP..6
(-5975 2550);
FORCEPROP 3 LASTPIN (-5925 2550) SIG_NAME M_H_CKE<2>
J 0
(-5915 2560);
DISPLAY 0.659574 (-5915 2560);
PAINT MONO (-5915 2560);
DISPLAY INVISIBLE (-5915 2560);
FORCEPROP 1 LASTPIN (-5925 2550) BN 2
J 0
(-5975 2560);
DISPLAY 0.617021 (-5975 2560);
PAINT PINK (-5975 2560);
FORCEPROP 2 LAST CDS_LIB mstr_standard
J 0
(-5975 2550);
DISPLAY 0.787234 (-5975 2550);
PAINT MONO (-5975 2550);
DISPLAY INVISIBLE (-5975 2550);
FORCEPROP 1 LAST BODY_TYPE PLUMBING
J 0
(-5975 2500);
DISPLAY 1.234043 (-5975 2500);
PAINT GREEN (-5975 2500);
DISPLAY INVISIBLE (-5975 2500);
FORCEPROP 1 LAST HDL_TAP TRUE
J 0
(-5650 2425);
DISPLAY 1.234043 (-5650 2425);
PAINT GREEN (-5650 2425);
DISPLAY INVISIBLE (-5650 2425);
FORCEPROP 1 LAST PATH I38
J 0
(-5977 2550);
DISPLAY 0.872340 (-5977 2550);
PAINT GREEN (-5977 2550);
DISPLAY INVISIBLE (-5977 2550);
FORCEADD TAP..6
(-5975 2750);
FORCEPROP 3 LASTPIN (-5925 2750) SIG_NAME M_H_CS_N<5>
J 0
(-5915 2760);
DISPLAY 0.659574 (-5915 2760);
PAINT MONO (-5915 2760);
DISPLAY INVISIBLE (-5915 2760);
FORCEPROP 1 LASTPIN (-5925 2750) BN 5
J 0
(-5975 2760);
DISPLAY 0.617021 (-5975 2760);
PAINT PINK (-5975 2760);
FORCEPROP 2 LAST CDS_LIB mstr_standard
J 0
(-5975 2750);
DISPLAY 0.787234 (-5975 2750);
PAINT MONO (-5975 2750);
DISPLAY INVISIBLE (-5975 2750);
FORCEPROP 1 LAST BODY_TYPE PLUMBING
J 0
(-5975 2700);
DISPLAY 1.234043 (-5975 2700);
PAINT GREEN (-5975 2700);
DISPLAY INVISIBLE (-5975 2700);
FORCEPROP 1 LAST HDL_TAP TRUE
J 0
(-5650 2625);
DISPLAY 1.234043 (-5650 2625);
PAINT GREEN (-5650 2625);
DISPLAY INVISIBLE (-5650 2625);
FORCEPROP 1 LAST PATH I39
J 0
(-5977 2750);
DISPLAY 0.872340 (-5977 2750);
PAINT GREEN (-5977 2750);
DISPLAY INVISIBLE (-5977 2750);
FORCEADD GND..1
(-7225 750);
FORCEPROP 3 LASTPIN (-7225 800) SIG_NAME GND\g
J 0
(-7215 810);
DISPLAY 0.659574 (-7215 810);
PAINT MONO (-7215 810);
DISPLAY INVISIBLE (-7215 810);
FORCEPROP 1 LAST VOLTAGE 0
J 0
(-7225 750);
PAINT SKYBLUE (-7225 750);
DISPLAY INVISIBLE (-7225 750);
FORCEPROP 2 LAST BOM_COST MEM
J 0
(-7225 755);
PAINT ORANGE (-7225 755);
DISPLAY INVISIBLE (-7225 755);
FORCEPROP 1 LAST SIZE 1B
J 0
(-7150 700);
DISPLAY 1.787234 (-7150 700);
PAINT GREEN (-7150 700);
DISPLAY INVISIBLE (-7150 700);
FORCEPROP 2 LAST CDS_LIB mstr_symbols
J 0
(-7225 750);
PAINT ORANGE (-7225 750);
DISPLAY INVISIBLE (-7225 750);
FORCEPROP 1 LAST BODY_TYPE PLUMBING
J 0
(-7270 707);
DISPLAY 0.340426 (-7270 707);
PAINT GREEN (-7270 707);
DISPLAY INVISIBLE (-7270 707);
FORCEPROP 1 LAST PATH I4
J 0
(-7150 750);
DISPLAY 0.872340 (-7150 750);
PAINT AQUA (-7150 750);
DISPLAY INVISIBLE (-7150 750);
FORCEPROP 2 LAST ROOM DDR4_GH_G
J 0
(-7225 755);
PAINT ORANGE (-7225 755);
DISPLAY INVISIBLE (-7225 755);
FORCEPROP 1 LAST HDL_POWER GND
J 0
(-7225 900);
DISPLAY 1.404255 (-7225 900);
PAINT GREEN (-7225 900);
DISPLAY INVISIBLE (-7225 900);
FORCEADD TAP..6
(-5975 2700);
FORCEPROP 3 LASTPIN (-5925 2700) SIG_NAME M_H_CS_N<4>
J 0
(-5915 2710);
DISPLAY 0.659574 (-5915 2710);
PAINT MONO (-5915 2710);
DISPLAY INVISIBLE (-5915 2710);
FORCEPROP 1 LASTPIN (-5925 2700) BN 4
J 0
(-5975 2710);
DISPLAY 0.617021 (-5975 2710);
PAINT PINK (-5975 2710);
FORCEPROP 2 LAST CDS_LIB mstr_standard
J 0
(-5975 2700);
DISPLAY 0.787234 (-5975 2700);
PAINT MONO (-5975 2700);
DISPLAY INVISIBLE (-5975 2700);
FORCEPROP 1 LAST BODY_TYPE PLUMBING
J 0
(-5975 2650);
DISPLAY 1.234043 (-5975 2650);
PAINT GREEN (-5975 2650);
DISPLAY INVISIBLE (-5975 2650);
FORCEPROP 1 LAST HDL_TAP TRUE
J 0
(-5650 2575);
DISPLAY 1.234043 (-5650 2575);
PAINT GREEN (-5650 2575);
DISPLAY INVISIBLE (-5650 2575);
FORCEPROP 1 LAST PATH I40
J 0
(-5977 2700);
DISPLAY 0.872340 (-5977 2700);
PAINT GREEN (-5977 2700);
DISPLAY INVISIBLE (-5977 2700);
FORCEADD TAP..6
(-5975 2850);
FORCEPROP 3 LASTPIN (-5925 2850) SIG_NAME M_H_CS_N<7>
J 0
(-5915 2860);
DISPLAY 0.659574 (-5915 2860);
PAINT MONO (-5915 2860);
DISPLAY INVISIBLE (-5915 2860);
FORCEPROP 1 LASTPIN (-5925 2850) BN 7
J 0
(-5975 2860);
DISPLAY 0.617021 (-5975 2860);
PAINT PINK (-5975 2860);
FORCEPROP 2 LAST CDS_LIB mstr_standard
J 0
(-5975 2850);
DISPLAY 0.787234 (-5975 2850);
PAINT MONO (-5975 2850);
DISPLAY INVISIBLE (-5975 2850);
FORCEPROP 1 LAST BODY_TYPE PLUMBING
J 0
(-5975 2800);
DISPLAY 1.234043 (-5975 2800);
PAINT GREEN (-5975 2800);
DISPLAY INVISIBLE (-5975 2800);
FORCEPROP 1 LAST HDL_TAP TRUE
J 0
(-5650 2725);
DISPLAY 1.234043 (-5650 2725);
PAINT GREEN (-5650 2725);
DISPLAY INVISIBLE (-5650 2725);
FORCEPROP 1 LAST PATH I41
J 0
(-5977 2850);
DISPLAY 0.872340 (-5977 2850);
PAINT GREEN (-5977 2850);
DISPLAY INVISIBLE (-5977 2850);
FORCEADD TAP..6
(-5975 2800);
FORCEPROP 3 LASTPIN (-5925 2800) SIG_NAME M_H_CS_N<6>
J 0
(-5915 2810);
DISPLAY 0.659574 (-5915 2810);
PAINT MONO (-5915 2810);
DISPLAY INVISIBLE (-5915 2810);
FORCEPROP 1 LASTPIN (-5925 2800) BN 6
J 0
(-5975 2810);
DISPLAY 0.617021 (-5975 2810);
PAINT PINK (-5975 2810);
FORCEPROP 2 LAST CDS_LIB mstr_standard
J 0
(-5975 2800);
DISPLAY 0.787234 (-5975 2800);
PAINT MONO (-5975 2800);
DISPLAY INVISIBLE (-5975 2800);
FORCEPROP 1 LAST BODY_TYPE PLUMBING
J 0
(-5975 2750);
DISPLAY 1.234043 (-5975 2750);
PAINT GREEN (-5975 2750);
DISPLAY INVISIBLE (-5975 2750);
FORCEPROP 1 LAST HDL_TAP TRUE
J 0
(-5650 2675);
DISPLAY 1.234043 (-5650 2675);
PAINT GREEN (-5650 2675);
DISPLAY INVISIBLE (-5650 2675);
FORCEPROP 1 LAST PATH I42
J 0
(-5977 2800);
DISPLAY 0.872340 (-5977 2800);
PAINT GREEN (-5977 2800);
DISPLAY INVISIBLE (-5977 2800);
FORCEADD TAP..6
(-5975 3150);
FORCEPROP 3 LASTPIN (-5925 3150) SIG_NAME M_H_CLK_DP<3>
J 0
(-5915 3160);
DISPLAY 0.659574 (-5915 3160);
PAINT MONO (-5915 3160);
DISPLAY INVISIBLE (-5915 3160);
FORCEPROP 1 LASTPIN (-5925 3150) BN 3
J 0
(-5975 3160);
DISPLAY 0.617021 (-5975 3160);
PAINT PINK (-5975 3160);
FORCEPROP 2 LAST CDS_LIB mstr_standard
J 0
(-5975 3150);
DISPLAY 0.787234 (-5975 3150);
PAINT MONO (-5975 3150);
DISPLAY INVISIBLE (-5975 3150);
FORCEPROP 1 LAST BODY_TYPE PLUMBING
J 0
(-5975 3100);
DISPLAY 1.234043 (-5975 3100);
PAINT GREEN (-5975 3100);
DISPLAY INVISIBLE (-5975 3100);
FORCEPROP 1 LAST HDL_TAP TRUE
J 0
(-5650 3025);
DISPLAY 1.234043 (-5650 3025);
PAINT GREEN (-5650 3025);
DISPLAY INVISIBLE (-5650 3025);
FORCEPROP 1 LAST PATH I43
J 0
(-5977 3150);
DISPLAY 0.872340 (-5977 3150);
PAINT GREEN (-5977 3150);
DISPLAY INVISIBLE (-5977 3150);
FORCEADD TAP..6
(-5975 3050);
FORCEPROP 3 LASTPIN (-5925 3050) SIG_NAME M_H_CLK_DP<2>
J 0
(-5915 3060);
DISPLAY 0.659574 (-5915 3060);
PAINT MONO (-5915 3060);
DISPLAY INVISIBLE (-5915 3060);
FORCEPROP 1 LASTPIN (-5925 3050) BN 2
J 0
(-5975 3060);
DISPLAY 0.617021 (-5975 3060);
PAINT PINK (-5975 3060);
FORCEPROP 2 LAST CDS_LIB mstr_standard
J 0
(-5975 3050);
DISPLAY 0.787234 (-5975 3050);
PAINT MONO (-5975 3050);
DISPLAY INVISIBLE (-5975 3050);
FORCEPROP 1 LAST BODY_TYPE PLUMBING
J 0
(-5975 3000);
DISPLAY 1.234043 (-5975 3000);
PAINT GREEN (-5975 3000);
DISPLAY INVISIBLE (-5975 3000);
FORCEPROP 1 LAST HDL_TAP TRUE
J 0
(-5650 2925);
DISPLAY 1.234043 (-5650 2925);
PAINT GREEN (-5650 2925);
DISPLAY INVISIBLE (-5650 2925);
FORCEPROP 1 LAST PATH I44
J 0
(-5977 3050);
DISPLAY 0.872340 (-5977 3050);
PAINT GREEN (-5977 3050);
DISPLAY INVISIBLE (-5977 3050);
FORCEADD TAP..6
(-5975 3250);
FORCEPROP 3 LASTPIN (-5925 3250) SIG_NAME M_H_BG<0>
J 0
(-5915 3260);
DISPLAY 0.659574 (-5915 3260);
PAINT MONO (-5915 3260);
DISPLAY INVISIBLE (-5915 3260);
FORCEPROP 1 LASTPIN (-5925 3250) BN 0
J 0
(-5975 3260);
DISPLAY 0.617021 (-5975 3260);
PAINT PINK (-5975 3260);
FORCEPROP 2 LAST CDS_LIB mstr_standard
J 0
(-5975 3250);
DISPLAY 0.787234 (-5975 3250);
PAINT MONO (-5975 3250);
DISPLAY INVISIBLE (-5975 3250);
FORCEPROP 1 LAST BODY_TYPE PLUMBING
J 0
(-5975 3200);
DISPLAY 1.234043 (-5975 3200);
PAINT GREEN (-5975 3200);
DISPLAY INVISIBLE (-5975 3200);
FORCEPROP 1 LAST HDL_TAP TRUE
J 0
(-5650 3125);
DISPLAY 1.234043 (-5650 3125);
PAINT GREEN (-5650 3125);
DISPLAY INVISIBLE (-5650 3125);
FORCEPROP 1 LAST PATH I45
J 0
(-5977 3250);
DISPLAY 0.872340 (-5977 3250);
PAINT GREEN (-5977 3250);
DISPLAY INVISIBLE (-5977 3250);
FORCEADD TAP..6
(-5975 3350);
FORCEPROP 3 LASTPIN (-5925 3350) SIG_NAME M_H_BA<0>
J 0
(-5915 3360);
DISPLAY 0.659574 (-5915 3360);
PAINT MONO (-5915 3360);
DISPLAY INVISIBLE (-5915 3360);
FORCEPROP 1 LASTPIN (-5925 3350) BN 0
J 0
(-5975 3360);
DISPLAY 0.617021 (-5975 3360);
PAINT PINK (-5975 3360);
FORCEPROP 2 LAST CDS_LIB mstr_standard
J 0
(-5975 3350);
DISPLAY 0.787234 (-5975 3350);
PAINT MONO (-5975 3350);
DISPLAY INVISIBLE (-5975 3350);
FORCEPROP 1 LAST BODY_TYPE PLUMBING
J 0
(-5975 3300);
DISPLAY 1.234043 (-5975 3300);
PAINT GREEN (-5975 3300);
DISPLAY INVISIBLE (-5975 3300);
FORCEPROP 1 LAST HDL_TAP TRUE
J 0
(-5650 3225);
DISPLAY 1.234043 (-5650 3225);
PAINT GREEN (-5650 3225);
DISPLAY INVISIBLE (-5650 3225);
FORCEPROP 1 LAST PATH I46
J 0
(-5977 3350);
DISPLAY 0.872340 (-5977 3350);
PAINT GREEN (-5977 3350);
DISPLAY INVISIBLE (-5977 3350);
FORCEADD TAP..6
(-5975 3300);
FORCEPROP 3 LASTPIN (-5925 3300) SIG_NAME M_H_BG<1>
J 0
(-5915 3310);
DISPLAY 0.659574 (-5915 3310);
PAINT MONO (-5915 3310);
DISPLAY INVISIBLE (-5915 3310);
FORCEPROP 1 LASTPIN (-5925 3300) BN 1
J 0
(-5975 3310);
DISPLAY 0.617021 (-5975 3310);
PAINT PINK (-5975 3310);
FORCEPROP 2 LAST CDS_LIB mstr_standard
J 0
(-5975 3300);
DISPLAY 0.787234 (-5975 3300);
PAINT MONO (-5975 3300);
DISPLAY INVISIBLE (-5975 3300);
FORCEPROP 1 LAST BODY_TYPE PLUMBING
J 0
(-5975 3250);
DISPLAY 1.234043 (-5975 3250);
PAINT GREEN (-5975 3250);
DISPLAY INVISIBLE (-5975 3250);
FORCEPROP 1 LAST HDL_TAP TRUE
J 0
(-5650 3175);
DISPLAY 1.234043 (-5650 3175);
PAINT GREEN (-5650 3175);
DISPLAY INVISIBLE (-5650 3175);
FORCEPROP 1 LAST PATH I47
J 0
(-5977 3300);
DISPLAY 0.872340 (-5977 3300);
PAINT GREEN (-5977 3300);
DISPLAY INVISIBLE (-5977 3300);
FORCEADD TAP..6
(-5975 3400);
FORCEPROP 3 LASTPIN (-5925 3400) SIG_NAME M_H_BA<1>
J 0
(-5915 3410);
DISPLAY 0.659574 (-5915 3410);
PAINT MONO (-5915 3410);
DISPLAY INVISIBLE (-5915 3410);
FORCEPROP 1 LASTPIN (-5925 3400) BN 1
J 0
(-5975 3410);
DISPLAY 0.617021 (-5975 3410);
PAINT PINK (-5975 3410);
FORCEPROP 2 LAST CDS_LIB mstr_standard
J 0
(-5975 3400);
DISPLAY 0.787234 (-5975 3400);
PAINT MONO (-5975 3400);
DISPLAY INVISIBLE (-5975 3400);
FORCEPROP 1 LAST BODY_TYPE PLUMBING
J 0
(-5975 3350);
DISPLAY 1.234043 (-5975 3350);
PAINT GREEN (-5975 3350);
DISPLAY INVISIBLE (-5975 3350);
FORCEPROP 1 LAST HDL_TAP TRUE
J 0
(-5650 3275);
DISPLAY 1.234043 (-5650 3275);
PAINT GREEN (-5650 3275);
DISPLAY INVISIBLE (-5650 3275);
FORCEPROP 1 LAST PATH I48
J 0
(-5977 3400);
DISPLAY 0.872340 (-5977 3400);
PAINT GREEN (-5977 3400);
DISPLAY INVISIBLE (-5977 3400);
FORCEADD TAP..6
(-5975 3500);
FORCEPROP 3 LASTPIN (-5925 3500) SIG_NAME M_H_MA<0>
J 0
(-5915 3510);
DISPLAY 0.659574 (-5915 3510);
PAINT MONO (-5915 3510);
DISPLAY INVISIBLE (-5915 3510);
FORCEPROP 1 LASTPIN (-5925 3500) BN 0
J 0
(-5975 3510);
DISPLAY 0.617021 (-5975 3510);
PAINT PINK (-5975 3510);
FORCEPROP 2 LAST CDS_LIB mstr_standard
J 2
(-5975 3500);
DISPLAY 0.787234 (-5975 3500);
PAINT MONO (-5975 3500);
DISPLAY INVISIBLE (-5975 3500);
FORCEPROP 1 LAST BODY_TYPE PLUMBING
J 0
(-5975 3450);
DISPLAY 1.234043 (-5975 3450);
PAINT GREEN (-5975 3450);
DISPLAY INVISIBLE (-5975 3450);
FORCEPROP 1 LAST HDL_TAP TRUE
J 0
(-5650 3375);
DISPLAY 1.234043 (-5650 3375);
PAINT GREEN (-5650 3375);
DISPLAY INVISIBLE (-5650 3375);
FORCEPROP 1 LAST PATH I49
J 0
(-5977 3500);
DISPLAY 0.872340 (-5977 3500);
PAINT GREEN (-5977 3500);
DISPLAY INVISIBLE (-5977 3500);
FORCEADD OFFPAGE..1
(-6625 900);
FORCEPROP 2 LAST $XR0 89 
J 0
(-6846 900);
DISPLAY 0.638298 (-6846 900);
PAINT MONO (-6846 900);
FORCEPROP 2 LAST $XR1 77 
J 0
(-6936 900);
DISPLAY 0.638298 (-6936 900);
PAINT MONO (-6936 900);
FORCEPROP 2 LAST $XR2 78 
J 0
(-7026 900);
DISPLAY 0.638298 (-7026 900);
PAINT MONO (-7026 900);
FORCEPROP 2 LAST $XR3 79 
J 0
(-7116 900);
DISPLAY 0.638298 (-7116 900);
PAINT MONO (-7116 900);
FORCEPROP 2 LAST $XR4 81 
J 0
(-7206 900);
DISPLAY 0.638298 (-7206 900);
PAINT MONO (-7206 900);
FORCEPROP 2 LAST $XR5 82 
J 0
(-6846 864);
DISPLAY 0.638298 (-6846 864);
PAINT MONO (-6846 864);
FORCEPROP 2 LAST CDS_LIB mstr_standard
J 0
(-6625 900);
PAINT ORANGE (-6625 900);
DISPLAY INVISIBLE (-6625 900);
FORCEPROP 1 LAST OFFPAGE TRUE
J 0
(-6300 775);
DISPLAY 0.936170 (-6300 775);
PAINT GREEN (-6300 775);
DISPLAY INVISIBLE (-6300 775);
FORCEPROP 1 LAST COMMENT_BODY TRUE
J 0
(-6500 800);
DISPLAY 0.936170 (-6500 800);
PAINT GREEN (-6500 800);
DISPLAY INVISIBLE (-6500 800);
FORCEPROP 2 LAST PATH I5
J 0
(-6900 950);
DISPLAY 1.021277 (-6900 950);
PAINT ORANGE (-6900 950);
DISPLAY INVISIBLE (-6900 950);
FORCEADD TAP..6
R 2
(-4475 1200);
FORCEPROP 3 LASTPIN (-4525 1200) SIG_NAME M_H_DQ<0>
J 0
(-4515 1210);
DISPLAY 0.659574 (-4515 1210);
PAINT MONO (-4515 1210);
DISPLAY INVISIBLE (-4515 1210);
FORCEPROP 1 LASTPIN (-4525 1200) BN 0
J 2
(-4475 1210);
DISPLAY 0.617021 (-4475 1210);
PAINT PINK (-4475 1210);
FORCEPROP 2 LAST CDS_LIB mstr_standard
J 2
(-4475 1200);
DISPLAY 0.787234 (-4475 1200);
PAINT MONO (-4475 1200);
DISPLAY INVISIBLE (-4475 1200);
FORCEPROP 1 LAST BODY_TYPE PLUMBING
J 2
(-4475 1150);
DISPLAY 1.234043 (-4475 1150);
PAINT GREEN (-4475 1150);
DISPLAY INVISIBLE (-4475 1150);
FORCEPROP 1 LAST HDL_TAP TRUE
J 2
(-4800 1075);
DISPLAY 1.234043 (-4800 1075);
PAINT GREEN (-4800 1075);
DISPLAY INVISIBLE (-4800 1075);
FORCEPROP 1 LAST PATH I50
J 2
(-4473 1200);
DISPLAY 0.872340 (-4473 1200);
PAINT GREEN (-4473 1200);
DISPLAY INVISIBLE (-4473 1200);
FORCEADD TAP..6
R 2
(-4475 1350);
FORCEPROP 3 LASTPIN (-4525 1350) SIG_NAME M_H_DQ<3>
J 0
(-4515 1360);
DISPLAY 0.659574 (-4515 1360);
PAINT MONO (-4515 1360);
DISPLAY INVISIBLE (-4515 1360);
FORCEPROP 1 LASTPIN (-4525 1350) BN 3
J 2
(-4475 1360);
DISPLAY 0.617021 (-4475 1360);
PAINT PINK (-4475 1360);
FORCEPROP 2 LAST CDS_LIB mstr_standard
J 2
(-4475 1350);
DISPLAY 0.787234 (-4475 1350);
PAINT MONO (-4475 1350);
DISPLAY INVISIBLE (-4475 1350);
FORCEPROP 1 LAST BODY_TYPE PLUMBING
J 2
(-4475 1300);
DISPLAY 1.234043 (-4475 1300);
PAINT GREEN (-4475 1300);
DISPLAY INVISIBLE (-4475 1300);
FORCEPROP 1 LAST HDL_TAP TRUE
J 2
(-4800 1225);
DISPLAY 1.234043 (-4800 1225);
PAINT GREEN (-4800 1225);
DISPLAY INVISIBLE (-4800 1225);
FORCEPROP 1 LAST PATH I51
J 2
(-4473 1350);
DISPLAY 0.872340 (-4473 1350);
PAINT GREEN (-4473 1350);
DISPLAY INVISIBLE (-4473 1350);
FORCEADD TAP..6
R 2
(-4475 1250);
FORCEPROP 3 LASTPIN (-4525 1250) SIG_NAME M_H_DQ<1>
J 0
(-4515 1260);
DISPLAY 0.659574 (-4515 1260);
PAINT MONO (-4515 1260);
DISPLAY INVISIBLE (-4515 1260);
FORCEPROP 1 LASTPIN (-4525 1250) BN 1
J 2
(-4475 1260);
DISPLAY 0.617021 (-4475 1260);
PAINT PINK (-4475 1260);
FORCEPROP 2 LAST CDS_LIB mstr_standard
J 2
(-4475 1250);
DISPLAY 0.787234 (-4475 1250);
PAINT MONO (-4475 1250);
DISPLAY INVISIBLE (-4475 1250);
FORCEPROP 1 LAST BODY_TYPE PLUMBING
J 2
(-4475 1200);
DISPLAY 1.234043 (-4475 1200);
PAINT GREEN (-4475 1200);
DISPLAY INVISIBLE (-4475 1200);
FORCEPROP 1 LAST HDL_TAP TRUE
J 2
(-4800 1125);
DISPLAY 1.234043 (-4800 1125);
PAINT GREEN (-4800 1125);
DISPLAY INVISIBLE (-4800 1125);
FORCEPROP 1 LAST PATH I52
J 2
(-4473 1250);
DISPLAY 0.872340 (-4473 1250);
PAINT GREEN (-4473 1250);
DISPLAY INVISIBLE (-4473 1250);
FORCEADD TAP..6
R 2
(-4475 1300);
FORCEPROP 3 LASTPIN (-4525 1300) SIG_NAME M_H_DQ<2>
J 0
(-4515 1310);
DISPLAY 0.659574 (-4515 1310);
PAINT MONO (-4515 1310);
DISPLAY INVISIBLE (-4515 1310);
FORCEPROP 1 LASTPIN (-4525 1300) BN 2
J 2
(-4475 1310);
DISPLAY 0.617021 (-4475 1310);
PAINT PINK (-4475 1310);
FORCEPROP 2 LAST CDS_LIB mstr_standard
J 2
(-4475 1300);
DISPLAY 0.787234 (-4475 1300);
PAINT MONO (-4475 1300);
DISPLAY INVISIBLE (-4475 1300);
FORCEPROP 1 LAST BODY_TYPE PLUMBING
J 2
(-4475 1250);
DISPLAY 1.234043 (-4475 1250);
PAINT GREEN (-4475 1250);
DISPLAY INVISIBLE (-4475 1250);
FORCEPROP 1 LAST HDL_TAP TRUE
J 2
(-4800 1175);
DISPLAY 1.234043 (-4800 1175);
PAINT GREEN (-4800 1175);
DISPLAY INVISIBLE (-4800 1175);
FORCEPROP 1 LAST PATH I53
J 2
(-4473 1300);
DISPLAY 0.872340 (-4473 1300);
PAINT GREEN (-4473 1300);
DISPLAY INVISIBLE (-4473 1300);
FORCEADD TAP..6
R 2
(-4475 1450);
FORCEPROP 3 LASTPIN (-4525 1450) SIG_NAME M_H_DQ<5>
J 0
(-4515 1460);
DISPLAY 0.659574 (-4515 1460);
PAINT MONO (-4515 1460);
DISPLAY INVISIBLE (-4515 1460);
FORCEPROP 1 LASTPIN (-4525 1450) BN 5
J 2
(-4475 1460);
DISPLAY 0.617021 (-4475 1460);
PAINT PINK (-4475 1460);
FORCEPROP 2 LAST CDS_LIB mstr_standard
J 2
(-4475 1450);
DISPLAY 0.787234 (-4475 1450);
PAINT MONO (-4475 1450);
DISPLAY INVISIBLE (-4475 1450);
FORCEPROP 1 LAST BODY_TYPE PLUMBING
J 2
(-4475 1400);
DISPLAY 1.234043 (-4475 1400);
PAINT GREEN (-4475 1400);
DISPLAY INVISIBLE (-4475 1400);
FORCEPROP 1 LAST HDL_TAP TRUE
J 2
(-4800 1325);
DISPLAY 1.234043 (-4800 1325);
PAINT GREEN (-4800 1325);
DISPLAY INVISIBLE (-4800 1325);
FORCEPROP 1 LAST PATH I54
J 2
(-4473 1450);
DISPLAY 0.872340 (-4473 1450);
PAINT GREEN (-4473 1450);
DISPLAY INVISIBLE (-4473 1450);
FORCEADD TAP..6
R 2
(-4475 1400);
FORCEPROP 3 LASTPIN (-4525 1400) SIG_NAME M_H_DQ<4>
J 0
(-4515 1410);
DISPLAY 0.659574 (-4515 1410);
PAINT MONO (-4515 1410);
DISPLAY INVISIBLE (-4515 1410);
FORCEPROP 1 LASTPIN (-4525 1400) BN 4
J 2
(-4475 1410);
DISPLAY 0.617021 (-4475 1410);
PAINT PINK (-4475 1410);
FORCEPROP 2 LAST CDS_LIB mstr_standard
J 2
(-4475 1400);
DISPLAY 0.787234 (-4475 1400);
PAINT MONO (-4475 1400);
DISPLAY INVISIBLE (-4475 1400);
FORCEPROP 1 LAST BODY_TYPE PLUMBING
J 2
(-4475 1350);
DISPLAY 1.234043 (-4475 1350);
PAINT GREEN (-4475 1350);
DISPLAY INVISIBLE (-4475 1350);
FORCEPROP 1 LAST HDL_TAP TRUE
J 2
(-4800 1275);
DISPLAY 1.234043 (-4800 1275);
PAINT GREEN (-4800 1275);
DISPLAY INVISIBLE (-4800 1275);
FORCEPROP 1 LAST PATH I55
J 2
(-4473 1400);
DISPLAY 0.872340 (-4473 1400);
PAINT GREEN (-4473 1400);
DISPLAY INVISIBLE (-4473 1400);
FORCEADD SCONN288_H44441003..4
(-3075 1450);
FORCEPROP 1 LAST LOCATION J9U1
J 0
(-3525 2550);
DISPLAY 0.617021 (-3525 2550);
PAINT AQUA (-3525 2550);
FORCEPROP 1 LAST PART_NUMBER H44441-003
J 0
(-3525 400);
DISPLAY 0.617021 (-3525 400);
PAINT BLUE (-3525 400);
FORCEPROP 1 LAST MATERIAL SCONN
J 0
(-3525 2500);
DISPLAY 0.617021 (-3525 2500);
PAINT SKYBLUE (-3525 2500);
FORCEPROP 2 LASTPIN (-3575 2000) $PN 77
J 2
(-3585 2010);
DISPLAY 0.617021 (-3585 2010);
PAINT ORANGE (-3585 2010);
FORCEPROP 2 LASTPIN (-3575 1950) $PN 221
J 2
(-3585 1960);
DISPLAY 0.617021 (-3585 1960);
PAINT ORANGE (-3585 1960);
FORCEPROP 2 LASTPIN (-3575 2300) $PN 142
J 2
(-3585 2310);
DISPLAY 0.617021 (-3585 2310);
PAINT ORANGE (-3585 2310);
FORCEPROP 2 LASTPIN (-3575 2250) $PN 143
J 2
(-3585 2260);
DISPLAY 0.617021 (-3585 2260);
PAINT ORANGE (-3585 2260);
FORCEPROP 2 LASTPIN (-3575 2200) $PN 288
J 2
(-3585 2210);
DISPLAY 0.617021 (-3585 2210);
PAINT ORANGE (-3585 2210);
FORCEPROP 2 LASTPIN (-3575 2150) $PN 286
J 2
(-3585 2160);
DISPLAY 0.617021 (-3585 2160);
PAINT ORANGE (-3585 2160);
FORCEPROP 2 LASTPIN (-3575 2100) $PN 287
J 2
(-3585 2110);
DISPLAY 0.617021 (-3585 2110);
PAINT ORANGE (-3585 2110);
FORCEPROP 2 LASTPIN (-3575 1850) $PN 59
J 2
(-3585 1860);
DISPLAY 0.617021 (-3585 1860);
PAINT ORANGE (-3585 1860);
FORCEPROP 2 LASTPIN (-3575 1800) $PN 61
J 2
(-3585 1810);
DISPLAY 0.617021 (-3585 1810);
PAINT ORANGE (-3585 1810);
FORCEPROP 2 LASTPIN (-3575 1750) $PN 64
J 2
(-3585 1760);
DISPLAY 0.617021 (-3585 1760);
PAINT ORANGE (-3585 1760);
FORCEPROP 2 LASTPIN (-3575 1700) $PN 67
J 2
(-3585 1710);
DISPLAY 0.617021 (-3585 1710);
PAINT ORANGE (-3585 1710);
FORCEPROP 2 LASTPIN (-3575 1650) $PN 70
J 2
(-3585 1660);
DISPLAY 0.617021 (-3585 1660);
PAINT ORANGE (-3585 1660);
FORCEPROP 2 LASTPIN (-3575 1600) $PN 73
J 2
(-3585 1610);
DISPLAY 0.617021 (-3585 1610);
PAINT ORANGE (-3585 1610);
FORCEPROP 2 LASTPIN (-3575 1550) $PN 76
J 2
(-3585 1560);
DISPLAY 0.617021 (-3585 1560);
PAINT ORANGE (-3585 1560);
FORCEPROP 2 LASTPIN (-3575 1500) $PN 80
J 2
(-3585 1510);
DISPLAY 0.617021 (-3585 1510);
PAINT ORANGE (-3585 1510);
FORCEPROP 2 LASTPIN (-3575 1450) $PN 83
J 2
(-3585 1460);
DISPLAY 0.617021 (-3585 1460);
PAINT ORANGE (-3585 1460);
FORCEPROP 2 LASTPIN (-3575 1400) $PN 85
J 2
(-3585 1410);
DISPLAY 0.617021 (-3585 1410);
PAINT ORANGE (-3585 1410);
FORCEPROP 2 LASTPIN (-3575 1350) $PN 88
J 2
(-3585 1360);
DISPLAY 0.617021 (-3585 1360);
PAINT ORANGE (-3585 1360);
FORCEPROP 2 LASTPIN (-3575 1300) $PN 90
J 2
(-3585 1310);
DISPLAY 0.617021 (-3585 1310);
PAINT ORANGE (-3585 1310);
FORCEPROP 2 LASTPIN (-3575 1250) $PN 92
J 2
(-3585 1260);
DISPLAY 0.617021 (-3585 1260);
PAINT ORANGE (-3585 1260);
FORCEPROP 2 LASTPIN (-3575 1200) $PN 204
J 2
(-3585 1210);
DISPLAY 0.617021 (-3585 1210);
PAINT ORANGE (-3585 1210);
FORCEPROP 2 LASTPIN (-3575 1150) $PN 206
J 2
(-3585 1160);
DISPLAY 0.617021 (-3585 1160);
PAINT ORANGE (-3585 1160);
FORCEPROP 2 LASTPIN (-3575 1100) $PN 209
J 2
(-3585 1110);
DISPLAY 0.617021 (-3585 1110);
PAINT ORANGE (-3585 1110);
FORCEPROP 2 LASTPIN (-3575 1050) $PN 212
J 2
(-3585 1060);
DISPLAY 0.617021 (-3585 1060);
PAINT ORANGE (-3585 1060);
FORCEPROP 2 LASTPIN (-3575 1000) $PN 215
J 2
(-3585 1010);
DISPLAY 0.617021 (-3585 1010);
PAINT ORANGE (-3585 1010);
FORCEPROP 2 LASTPIN (-3575 950) $PN 217
J 2
(-3585 960);
DISPLAY 0.617021 (-3585 960);
PAINT ORANGE (-3585 960);
FORCEPROP 2 LASTPIN (-3575 900) $PN 220
J 2
(-3585 910);
DISPLAY 0.617021 (-3585 910);
PAINT ORANGE (-3585 910);
FORCEPROP 2 LASTPIN (-3575 850) $PN 223
J 2
(-3585 860);
DISPLAY 0.617021 (-3585 860);
PAINT ORANGE (-3585 860);
FORCEPROP 2 LASTPIN (-3575 800) $PN 226
J 2
(-3585 810);
DISPLAY 0.617021 (-3585 810);
PAINT ORANGE (-3585 810);
FORCEPROP 2 LASTPIN (-3575 750) $PN 229
J 2
(-3585 760);
DISPLAY 0.617021 (-3585 760);
PAINT ORANGE (-3585 760);
FORCEPROP 2 LASTPIN (-3575 700) $PN 231
J 2
(-3585 710);
DISPLAY 0.617021 (-3585 710);
PAINT ORANGE (-3585 710);
FORCEPROP 2 LASTPIN (-3575 650) $PN 233
J 2
(-3585 660);
DISPLAY 0.617021 (-3585 660);
PAINT ORANGE (-3585 660);
FORCEPROP 2 LASTPIN (-3575 600) $PN 236
J 2
(-3585 610);
DISPLAY 0.617021 (-3585 610);
PAINT ORANGE (-3585 610);
FORCEPROP 2 LASTPIN (-2575 2300) $PN 1
J 0
(-2565 2310);
DISPLAY 0.617021 (-2565 2310);
PAINT ORANGE (-2565 2310);
FORCEPROP 2 LASTPIN (-2575 2250) $PN 145
J 0
(-2565 2260);
DISPLAY 0.617021 (-2565 2260);
PAINT ORANGE (-2565 2260);
FORCEPROP 1 LAST PACK_TYPE PIP
J 0
(-3525 2600);
PAINT SKYBLUE (-3525 2600);
DISPLAY INVISIBLE (-3525 2600);
FORCEPROP 2 LAST BOM_COST MEM
J 0
(-3075 1450);
PAINT ORANGE (-3075 1450);
DISPLAY INVISIBLE (-3075 1450);
FORCEPROP 2 LAST CDS_LIB mstr_sconn
J 0
(-3075 1450);
PAINT ORANGE (-3075 1450);
DISPLAY INVISIBLE (-3075 1450);
FORCEPROP 2 LAST SEC_TYPE PIP
J 0
(-3525 2600);
DISPLAY 1.021277 (-3525 2600);
PAINT ORANGE (-3525 2600);
DISPLAY INVISIBLE (-3525 2600);
FORCEPROP 2 LAST SEC 4
J 0
(-3525 2600);
DISPLAY 0.680851 (-3525 2600);
PAINT MONO (-3525 2600);
DISPLAY INVISIBLE (-3525 2600);
FORCEPROP 2 LAST CDS_LOCATION J9U1
J 0
(-3525 2550);
DISPLAY 0.617021 (-3525 2550);
PAINT AQUA (-3525 2550);
DISPLAY INVISIBLE (-3525 2550);
FORCEPROP 1 LAST PATH I56
J 0
(-3075 2500);
PAINT GREEN (-3075 2500);
DISPLAY INVISIBLE (-3075 2500);
FORCEPROP 2 LAST ROOM DDR4_GH_H
J 0
(-3075 1450);
PAINT ORANGE (-3075 1450);
DISPLAY INVISIBLE (-3075 1450);
FORCEADD TAP..6
R 2
(-4475 1550);
FORCEPROP 3 LASTPIN (-4525 1550) SIG_NAME M_H_DQ<7>
J 0
(-4515 1560);
DISPLAY 0.659574 (-4515 1560);
PAINT MONO (-4515 1560);
DISPLAY INVISIBLE (-4515 1560);
FORCEPROP 1 LASTPIN (-4525 1550) BN 7
J 2
(-4475 1560);
DISPLAY 0.617021 (-4475 1560);
PAINT PINK (-4475 1560);
FORCEPROP 2 LAST CDS_LIB mstr_standard
J 2
(-4475 1550);
DISPLAY 0.787234 (-4475 1550);
PAINT MONO (-4475 1550);
DISPLAY INVISIBLE (-4475 1550);
FORCEPROP 1 LAST BODY_TYPE PLUMBING
J 2
(-4475 1500);
DISPLAY 1.234043 (-4475 1500);
PAINT GREEN (-4475 1500);
DISPLAY INVISIBLE (-4475 1500);
FORCEPROP 1 LAST HDL_TAP TRUE
J 2
(-4800 1425);
DISPLAY 1.234043 (-4800 1425);
PAINT GREEN (-4800 1425);
DISPLAY INVISIBLE (-4800 1425);
FORCEPROP 1 LAST PATH I57
J 2
(-4473 1550);
DISPLAY 0.872340 (-4473 1550);
PAINT GREEN (-4473 1550);
DISPLAY INVISIBLE (-4473 1550);
FORCEADD TAP..6
R 2
(-4475 1500);
FORCEPROP 3 LASTPIN (-4525 1500) SIG_NAME M_H_DQ<6>
J 0
(-4515 1510);
DISPLAY 0.659574 (-4515 1510);
PAINT MONO (-4515 1510);
DISPLAY INVISIBLE (-4515 1510);
FORCEPROP 1 LASTPIN (-4525 1500) BN 6
J 2
(-4475 1510);
DISPLAY 0.617021 (-4475 1510);
PAINT PINK (-4475 1510);
FORCEPROP 2 LAST CDS_LIB mstr_standard
J 2
(-4475 1500);
DISPLAY 0.787234 (-4475 1500);
PAINT MONO (-4475 1500);
DISPLAY INVISIBLE (-4475 1500);
FORCEPROP 1 LAST BODY_TYPE PLUMBING
J 2
(-4475 1450);
DISPLAY 1.234043 (-4475 1450);
PAINT GREEN (-4475 1450);
DISPLAY INVISIBLE (-4475 1450);
FORCEPROP 1 LAST HDL_TAP TRUE
J 2
(-4800 1375);
DISPLAY 1.234043 (-4800 1375);
PAINT GREEN (-4800 1375);
DISPLAY INVISIBLE (-4800 1375);
FORCEPROP 1 LAST PATH I58
J 2
(-4473 1500);
DISPLAY 0.872340 (-4473 1500);
PAINT GREEN (-4473 1500);
DISPLAY INVISIBLE (-4473 1500);
FORCEADD TAP..6
R 2
(-4475 1600);
FORCEPROP 3 LASTPIN (-4525 1600) SIG_NAME M_H_DQ<8>
J 0
(-4515 1610);
DISPLAY 0.659574 (-4515 1610);
PAINT MONO (-4515 1610);
DISPLAY INVISIBLE (-4515 1610);
FORCEPROP 1 LASTPIN (-4525 1600) BN 8
J 2
(-4475 1610);
DISPLAY 0.617021 (-4475 1610);
PAINT PINK (-4475 1610);
FORCEPROP 2 LAST CDS_LIB mstr_standard
J 2
(-4475 1600);
DISPLAY 0.787234 (-4475 1600);
PAINT MONO (-4475 1600);
DISPLAY INVISIBLE (-4475 1600);
FORCEPROP 1 LAST BODY_TYPE PLUMBING
J 2
(-4475 1550);
DISPLAY 1.234043 (-4475 1550);
PAINT GREEN (-4475 1550);
DISPLAY INVISIBLE (-4475 1550);
FORCEPROP 1 LAST HDL_TAP TRUE
J 2
(-4800 1475);
DISPLAY 1.234043 (-4800 1475);
PAINT GREEN (-4800 1475);
DISPLAY INVISIBLE (-4800 1475);
FORCEPROP 1 LAST PATH I59
J 2
(-4473 1600);
DISPLAY 0.872340 (-4473 1600);
PAINT GREEN (-4473 1600);
DISPLAY INVISIBLE (-4473 1600);
FORCEADD OFFPAGE..1
(-6625 1300);
FORCEPROP 2 LAST $XR0 99 
J 0
(-6876 1300);
DISPLAY 0.638298 (-6876 1300);
PAINT MONO (-6876 1300);
FORCEPROP 2 LAST $XR1 77 
J 0
(-6966 1300);
DISPLAY 0.638298 (-6966 1300);
PAINT MONO (-6966 1300);
FORCEPROP 2 LAST $XR2 78 
J 0
(-7056 1300);
DISPLAY 0.638298 (-7056 1300);
PAINT MONO (-7056 1300);
FORCEPROP 2 LAST $XR3 79 
J 0
(-7146 1300);
DISPLAY 0.638298 (-7146 1300);
PAINT MONO (-7146 1300);
FORCEPROP 2 LAST $XR4 81 
J 0
(-7236 1300);
DISPLAY 0.638298 (-7236 1300);
PAINT MONO (-7236 1300);
FORCEPROP 2 LAST $XR5 82 
J 0
(-7326 1300);
DISPLAY 0.638298 (-7326 1300);
PAINT MONO (-7326 1300);
FORCEPROP 2 LAST CDS_LIB mstr_standard
J 0
(-6625 1300);
DISPLAY 0.787234 (-6625 1300);
PAINT MONO (-6625 1300);
DISPLAY INVISIBLE (-6625 1300);
FORCEPROP 1 LAST OFFPAGE TRUE
J 0
(-6300 1175);
DISPLAY 0.936170 (-6300 1175);
PAINT GREEN (-6300 1175);
DISPLAY INVISIBLE (-6300 1175);
FORCEPROP 1 LAST COMMENT_BODY TRUE
J 0
(-6500 1200);
DISPLAY 0.936170 (-6500 1200);
PAINT GREEN (-6500 1200);
DISPLAY INVISIBLE (-6500 1200);
FORCEPROP 2 LAST PATH I6
J 0
(-6875 1350);
DISPLAY 1.021277 (-6875 1350);
PAINT ORANGE (-6875 1350);
DISPLAY INVISIBLE (-6875 1350);
FORCEADD TAP..6
R 2
(-4475 1650);
FORCEPROP 3 LASTPIN (-4525 1650) SIG_NAME M_H_DQ<9>
J 0
(-4515 1660);
DISPLAY 0.659574 (-4515 1660);
PAINT MONO (-4515 1660);
DISPLAY INVISIBLE (-4515 1660);
FORCEPROP 1 LASTPIN (-4525 1650) BN 9
J 2
(-4475 1660);
DISPLAY 0.617021 (-4475 1660);
PAINT PINK (-4475 1660);
FORCEPROP 2 LAST CDS_LIB mstr_standard
J 2
(-4475 1650);
DISPLAY 0.787234 (-4475 1650);
PAINT MONO (-4475 1650);
DISPLAY INVISIBLE (-4475 1650);
FORCEPROP 1 LAST BODY_TYPE PLUMBING
J 2
(-4475 1600);
DISPLAY 1.234043 (-4475 1600);
PAINT GREEN (-4475 1600);
DISPLAY INVISIBLE (-4475 1600);
FORCEPROP 1 LAST HDL_TAP TRUE
J 2
(-4800 1525);
DISPLAY 1.234043 (-4800 1525);
PAINT GREEN (-4800 1525);
DISPLAY INVISIBLE (-4800 1525);
FORCEPROP 1 LAST PATH I60
J 2
(-4473 1650);
DISPLAY 0.872340 (-4473 1650);
PAINT GREEN (-4473 1650);
DISPLAY INVISIBLE (-4473 1650);
FORCEADD TAP..6
R 2
(-4475 1700);
FORCEPROP 3 LASTPIN (-4525 1700) SIG_NAME M_H_DQ<10>
J 0
(-4515 1710);
DISPLAY 0.659574 (-4515 1710);
PAINT MONO (-4515 1710);
DISPLAY INVISIBLE (-4515 1710);
FORCEPROP 1 LASTPIN (-4525 1700) BN 10
J 2
(-4475 1710);
DISPLAY 0.617021 (-4475 1710);
PAINT PINK (-4475 1710);
FORCEPROP 2 LAST CDS_LIB mstr_standard
J 2
(-4475 1700);
DISPLAY 0.787234 (-4475 1700);
PAINT MONO (-4475 1700);
DISPLAY INVISIBLE (-4475 1700);
FORCEPROP 1 LAST BODY_TYPE PLUMBING
J 2
(-4475 1650);
DISPLAY 1.234043 (-4475 1650);
PAINT GREEN (-4475 1650);
DISPLAY INVISIBLE (-4475 1650);
FORCEPROP 1 LAST HDL_TAP TRUE
J 2
(-4800 1575);
DISPLAY 1.234043 (-4800 1575);
PAINT GREEN (-4800 1575);
DISPLAY INVISIBLE (-4800 1575);
FORCEPROP 1 LAST PATH I61
J 2
(-4473 1700);
DISPLAY 0.872340 (-4473 1700);
PAINT GREEN (-4473 1700);
DISPLAY INVISIBLE (-4473 1700);
FORCEADD TAP..6
R 2
(-4475 1750);
FORCEPROP 3 LASTPIN (-4525 1750) SIG_NAME M_H_DQ<11>
J 0
(-4515 1760);
DISPLAY 0.659574 (-4515 1760);
PAINT MONO (-4515 1760);
DISPLAY INVISIBLE (-4515 1760);
FORCEPROP 1 LASTPIN (-4525 1750) BN 11
J 2
(-4475 1760);
DISPLAY 0.617021 (-4475 1760);
PAINT PINK (-4475 1760);
FORCEPROP 2 LAST CDS_LIB mstr_standard
J 2
(-4475 1750);
DISPLAY 0.787234 (-4475 1750);
PAINT MONO (-4475 1750);
DISPLAY INVISIBLE (-4475 1750);
FORCEPROP 1 LAST BODY_TYPE PLUMBING
J 2
(-4475 1700);
DISPLAY 1.234043 (-4475 1700);
PAINT GREEN (-4475 1700);
DISPLAY INVISIBLE (-4475 1700);
FORCEPROP 1 LAST HDL_TAP TRUE
J 2
(-4800 1625);
DISPLAY 1.234043 (-4800 1625);
PAINT GREEN (-4800 1625);
DISPLAY INVISIBLE (-4800 1625);
FORCEPROP 1 LAST PATH I62
J 2
(-4473 1750);
DISPLAY 0.872340 (-4473 1750);
PAINT GREEN (-4473 1750);
DISPLAY INVISIBLE (-4473 1750);
FORCEADD TAP..6
R 2
(-4475 1850);
FORCEPROP 3 LASTPIN (-4525 1850) SIG_NAME M_H_DQ<13>
J 0
(-4515 1860);
DISPLAY 0.659574 (-4515 1860);
PAINT MONO (-4515 1860);
DISPLAY INVISIBLE (-4515 1860);
FORCEPROP 1 LASTPIN (-4525 1850) BN 13
J 2
(-4475 1860);
DISPLAY 0.617021 (-4475 1860);
PAINT PINK (-4475 1860);
FORCEPROP 2 LAST CDS_LIB mstr_standard
J 2
(-4475 1850);
DISPLAY 0.787234 (-4475 1850);
PAINT MONO (-4475 1850);
DISPLAY INVISIBLE (-4475 1850);
FORCEPROP 1 LAST BODY_TYPE PLUMBING
J 2
(-4475 1800);
DISPLAY 1.234043 (-4475 1800);
PAINT GREEN (-4475 1800);
DISPLAY INVISIBLE (-4475 1800);
FORCEPROP 1 LAST HDL_TAP TRUE
J 2
(-4800 1725);
DISPLAY 1.234043 (-4800 1725);
PAINT GREEN (-4800 1725);
DISPLAY INVISIBLE (-4800 1725);
FORCEPROP 1 LAST PATH I63
J 2
(-4473 1850);
DISPLAY 0.872340 (-4473 1850);
PAINT GREEN (-4473 1850);
DISPLAY INVISIBLE (-4473 1850);
FORCEADD TAP..6
R 2
(-4475 1800);
FORCEPROP 3 LASTPIN (-4525 1800) SIG_NAME M_H_DQ<12>
J 0
(-4515 1810);
DISPLAY 0.659574 (-4515 1810);
PAINT MONO (-4515 1810);
DISPLAY INVISIBLE (-4515 1810);
FORCEPROP 1 LASTPIN (-4525 1800) BN 12
J 2
(-4475 1810);
DISPLAY 0.617021 (-4475 1810);
PAINT PINK (-4475 1810);
FORCEPROP 2 LAST CDS_LIB mstr_standard
J 2
(-4475 1800);
DISPLAY 0.787234 (-4475 1800);
PAINT MONO (-4475 1800);
DISPLAY INVISIBLE (-4475 1800);
FORCEPROP 1 LAST BODY_TYPE PLUMBING
J 2
(-4475 1750);
DISPLAY 1.234043 (-4475 1750);
PAINT GREEN (-4475 1750);
DISPLAY INVISIBLE (-4475 1750);
FORCEPROP 1 LAST HDL_TAP TRUE
J 2
(-4800 1675);
DISPLAY 1.234043 (-4800 1675);
PAINT GREEN (-4800 1675);
DISPLAY INVISIBLE (-4800 1675);
FORCEPROP 1 LAST PATH I64
J 2
(-4473 1800);
DISPLAY 0.872340 (-4473 1800);
PAINT GREEN (-4473 1800);
DISPLAY INVISIBLE (-4473 1800);
FORCEADD TAP..6
R 2
(-4475 2000);
FORCEPROP 3 LASTPIN (-4525 2000) SIG_NAME M_H_DQ<16>
J 0
(-4515 2010);
DISPLAY 0.659574 (-4515 2010);
PAINT MONO (-4515 2010);
DISPLAY INVISIBLE (-4515 2010);
FORCEPROP 1 LASTPIN (-4525 2000) BN 16
J 2
(-4475 2010);
DISPLAY 0.617021 (-4475 2010);
PAINT PINK (-4475 2010);
FORCEPROP 2 LAST CDS_LIB mstr_standard
J 2
(-4475 2000);
DISPLAY 0.787234 (-4475 2000);
PAINT MONO (-4475 2000);
DISPLAY INVISIBLE (-4475 2000);
FORCEPROP 1 LAST BODY_TYPE PLUMBING
J 2
(-4475 1950);
DISPLAY 1.234043 (-4475 1950);
PAINT GREEN (-4475 1950);
DISPLAY INVISIBLE (-4475 1950);
FORCEPROP 1 LAST HDL_TAP TRUE
J 2
(-4800 1875);
DISPLAY 1.234043 (-4800 1875);
PAINT GREEN (-4800 1875);
DISPLAY INVISIBLE (-4800 1875);
FORCEPROP 1 LAST PATH I65
J 2
(-4473 2000);
DISPLAY 0.872340 (-4473 2000);
PAINT GREEN (-4473 2000);
DISPLAY INVISIBLE (-4473 2000);
FORCEADD TAP..6
R 2
(-4475 1900);
FORCEPROP 3 LASTPIN (-4525 1900) SIG_NAME M_H_DQ<14>
J 0
(-4515 1910);
DISPLAY 0.659574 (-4515 1910);
PAINT MONO (-4515 1910);
DISPLAY INVISIBLE (-4515 1910);
FORCEPROP 1 LASTPIN (-4525 1900) BN 14
J 2
(-4475 1910);
DISPLAY 0.617021 (-4475 1910);
PAINT PINK (-4475 1910);
FORCEPROP 2 LAST CDS_LIB mstr_standard
J 2
(-4475 1900);
DISPLAY 0.787234 (-4475 1900);
PAINT MONO (-4475 1900);
DISPLAY INVISIBLE (-4475 1900);
FORCEPROP 1 LAST BODY_TYPE PLUMBING
J 2
(-4475 1850);
DISPLAY 1.234043 (-4475 1850);
PAINT GREEN (-4475 1850);
DISPLAY INVISIBLE (-4475 1850);
FORCEPROP 1 LAST HDL_TAP TRUE
J 2
(-4800 1775);
DISPLAY 1.234043 (-4800 1775);
PAINT GREEN (-4800 1775);
DISPLAY INVISIBLE (-4800 1775);
FORCEPROP 1 LAST PATH I66
J 2
(-4473 1900);
DISPLAY 0.872340 (-4473 1900);
PAINT GREEN (-4473 1900);
DISPLAY INVISIBLE (-4473 1900);
FORCEADD TAP..6
R 2
(-4475 1950);
FORCEPROP 3 LASTPIN (-4525 1950) SIG_NAME M_H_DQ<15>
J 0
(-4515 1960);
DISPLAY 0.659574 (-4515 1960);
PAINT MONO (-4515 1960);
DISPLAY INVISIBLE (-4515 1960);
FORCEPROP 1 LASTPIN (-4525 1950) BN 15
J 2
(-4475 1960);
DISPLAY 0.617021 (-4475 1960);
PAINT PINK (-4475 1960);
FORCEPROP 2 LAST CDS_LIB mstr_standard
J 2
(-4475 1950);
DISPLAY 0.787234 (-4475 1950);
PAINT MONO (-4475 1950);
DISPLAY INVISIBLE (-4475 1950);
FORCEPROP 1 LAST BODY_TYPE PLUMBING
J 2
(-4475 1900);
DISPLAY 1.234043 (-4475 1900);
PAINT GREEN (-4475 1900);
DISPLAY INVISIBLE (-4475 1900);
FORCEPROP 1 LAST HDL_TAP TRUE
J 2
(-4800 1825);
DISPLAY 1.234043 (-4800 1825);
PAINT GREEN (-4800 1825);
DISPLAY INVISIBLE (-4800 1825);
FORCEPROP 1 LAST PATH I67
J 2
(-4473 1950);
DISPLAY 0.872340 (-4473 1950);
PAINT GREEN (-4473 1950);
DISPLAY INVISIBLE (-4473 1950);
FORCEADD TAP..6
R 2
(-4475 2050);
FORCEPROP 3 LASTPIN (-4525 2050) SIG_NAME M_H_DQ<17>
J 0
(-4515 2060);
DISPLAY 0.659574 (-4515 2060);
PAINT MONO (-4515 2060);
DISPLAY INVISIBLE (-4515 2060);
FORCEPROP 1 LASTPIN (-4525 2050) BN 17
J 2
(-4475 2060);
DISPLAY 0.617021 (-4475 2060);
PAINT PINK (-4475 2060);
FORCEPROP 2 LAST CDS_LIB mstr_standard
J 2
(-4475 2050);
DISPLAY 0.787234 (-4475 2050);
PAINT MONO (-4475 2050);
DISPLAY INVISIBLE (-4475 2050);
FORCEPROP 1 LAST BODY_TYPE PLUMBING
J 2
(-4475 2000);
DISPLAY 1.234043 (-4475 2000);
PAINT GREEN (-4475 2000);
DISPLAY INVISIBLE (-4475 2000);
FORCEPROP 1 LAST HDL_TAP TRUE
J 2
(-4800 1925);
DISPLAY 1.234043 (-4800 1925);
PAINT GREEN (-4800 1925);
DISPLAY INVISIBLE (-4800 1925);
FORCEPROP 1 LAST PATH I68
J 2
(-4473 2050);
DISPLAY 0.872340 (-4473 2050);
PAINT GREEN (-4473 2050);
DISPLAY INVISIBLE (-4473 2050);
FORCEADD TAP..6
R 2
(-4475 2100);
FORCEPROP 3 LASTPIN (-4525 2100) SIG_NAME M_H_DQ<18>
J 0
(-4515 2110);
DISPLAY 0.659574 (-4515 2110);
PAINT MONO (-4515 2110);
DISPLAY INVISIBLE (-4515 2110);
FORCEPROP 1 LASTPIN (-4525 2100) BN 18
J 2
(-4475 2110);
DISPLAY 0.617021 (-4475 2110);
PAINT PINK (-4475 2110);
FORCEPROP 2 LAST CDS_LIB mstr_standard
J 2
(-4475 2100);
DISPLAY 0.787234 (-4475 2100);
PAINT MONO (-4475 2100);
DISPLAY INVISIBLE (-4475 2100);
FORCEPROP 1 LAST BODY_TYPE PLUMBING
J 2
(-4475 2050);
DISPLAY 1.234043 (-4475 2050);
PAINT GREEN (-4475 2050);
DISPLAY INVISIBLE (-4475 2050);
FORCEPROP 1 LAST HDL_TAP TRUE
J 2
(-4800 1975);
DISPLAY 1.234043 (-4800 1975);
PAINT GREEN (-4800 1975);
DISPLAY INVISIBLE (-4800 1975);
FORCEPROP 1 LAST PATH I69
J 2
(-4473 2100);
DISPLAY 0.872340 (-4473 2100);
PAINT GREEN (-4473 2100);
DISPLAY INVISIBLE (-4473 2100);
FORCEADD OFFPAGE..6
(-6625 1350);
FORCEPROP 2 LAST $XR0 77 
J 0
(-6874 1350);
DISPLAY 0.638298 (-6874 1350);
PAINT MONO (-6874 1350);
FORCEPROP 2 LAST $XR1 78 
J 0
(-6964 1350);
DISPLAY 0.638298 (-6964 1350);
PAINT MONO (-6964 1350);
FORCEPROP 2 LAST $XR2 79 
J 0
(-7054 1350);
DISPLAY 0.638298 (-7054 1350);
PAINT MONO (-7054 1350);
FORCEPROP 2 LAST $XR3 81 
J 0
(-7144 1350);
DISPLAY 0.638298 (-7144 1350);
PAINT MONO (-7144 1350);
FORCEPROP 2 LAST $XR4 82 
J 0
(-7234 1350);
DISPLAY 0.638298 (-7234 1350);
PAINT MONO (-7234 1350);
FORCEPROP 2 LAST $XR5 99 
J 0
(-7324 1350);
DISPLAY 0.638298 (-7324 1350);
PAINT MONO (-7324 1350);
FORCEPROP 2 LASTPIN (-6575 1350) SIG_NAME SMB_DDR_GHJ_VPP_SDA
J 0
(-6535 1360);
DISPLAY 0.617021 (-6535 1360);
PAINT ORANGE (-6535 1360);
FORCEPROP 2 LAST CDS_LIB mstr_standard
J 0
(-6625 1350);
DISPLAY 0.787234 (-6625 1350);
PAINT MONO (-6625 1350);
DISPLAY INVISIBLE (-6625 1350);
FORCEPROP 1 LAST OFFPAGE TRUE
J 0
(-6300 1225);
DISPLAY 0.936170 (-6300 1225);
PAINT GREEN (-6300 1225);
DISPLAY INVISIBLE (-6300 1225);
FORCEPROP 1 LAST COMMENT_BODY TRUE
J 0
(-6525 1275);
DISPLAY 0.936170 (-6525 1275);
PAINT GREEN (-6525 1275);
DISPLAY INVISIBLE (-6525 1275);
FORCEPROP 2 LAST PATH I7
J 0
(-6850 1400);
DISPLAY 1.021277 (-6850 1400);
PAINT ORANGE (-6850 1400);
DISPLAY INVISIBLE (-6850 1400);
FORCEADD TAP..6
R 2
(-4475 2250);
FORCEPROP 3 LASTPIN (-4525 2250) SIG_NAME M_H_DQ<21>
J 0
(-4515 2260);
DISPLAY 0.659574 (-4515 2260);
PAINT MONO (-4515 2260);
DISPLAY INVISIBLE (-4515 2260);
FORCEPROP 1 LASTPIN (-4525 2250) BN 21
J 2
(-4475 2260);
DISPLAY 0.617021 (-4475 2260);
PAINT PINK (-4475 2260);
FORCEPROP 2 LAST CDS_LIB mstr_standard
J 2
(-4475 2250);
DISPLAY 0.787234 (-4475 2250);
PAINT MONO (-4475 2250);
DISPLAY INVISIBLE (-4475 2250);
FORCEPROP 1 LAST BODY_TYPE PLUMBING
J 2
(-4475 2200);
DISPLAY 1.234043 (-4475 2200);
PAINT GREEN (-4475 2200);
DISPLAY INVISIBLE (-4475 2200);
FORCEPROP 1 LAST HDL_TAP TRUE
J 2
(-4800 2125);
DISPLAY 1.234043 (-4800 2125);
PAINT GREEN (-4800 2125);
DISPLAY INVISIBLE (-4800 2125);
FORCEPROP 1 LAST PATH I70
J 2
(-4473 2250);
DISPLAY 0.872340 (-4473 2250);
PAINT GREEN (-4473 2250);
DISPLAY INVISIBLE (-4473 2250);
FORCEADD TAP..6
R 2
(-4475 2150);
FORCEPROP 3 LASTPIN (-4525 2150) SIG_NAME M_H_DQ<19>
J 0
(-4515 2160);
DISPLAY 0.659574 (-4515 2160);
PAINT MONO (-4515 2160);
DISPLAY INVISIBLE (-4515 2160);
FORCEPROP 1 LASTPIN (-4525 2150) BN 19
J 2
(-4475 2160);
DISPLAY 0.617021 (-4475 2160);
PAINT PINK (-4475 2160);
FORCEPROP 2 LAST CDS_LIB mstr_standard
J 2
(-4475 2150);
DISPLAY 0.787234 (-4475 2150);
PAINT MONO (-4475 2150);
DISPLAY INVISIBLE (-4475 2150);
FORCEPROP 1 LAST BODY_TYPE PLUMBING
J 2
(-4475 2100);
DISPLAY 1.234043 (-4475 2100);
PAINT GREEN (-4475 2100);
DISPLAY INVISIBLE (-4475 2100);
FORCEPROP 1 LAST HDL_TAP TRUE
J 2
(-4800 2025);
DISPLAY 1.234043 (-4800 2025);
PAINT GREEN (-4800 2025);
DISPLAY INVISIBLE (-4800 2025);
FORCEPROP 1 LAST PATH I71
J 2
(-4473 2150);
DISPLAY 0.872340 (-4473 2150);
PAINT GREEN (-4473 2150);
DISPLAY INVISIBLE (-4473 2150);
FORCEADD TAP..6
R 2
(-4475 2200);
FORCEPROP 3 LASTPIN (-4525 2200) SIG_NAME M_H_DQ<20>
J 0
(-4515 2210);
DISPLAY 0.659574 (-4515 2210);
PAINT MONO (-4515 2210);
DISPLAY INVISIBLE (-4515 2210);
FORCEPROP 1 LASTPIN (-4525 2200) BN 20
J 2
(-4475 2210);
DISPLAY 0.617021 (-4475 2210);
PAINT PINK (-4475 2210);
FORCEPROP 2 LAST CDS_LIB mstr_standard
J 2
(-4475 2200);
DISPLAY 0.787234 (-4475 2200);
PAINT MONO (-4475 2200);
DISPLAY INVISIBLE (-4475 2200);
FORCEPROP 1 LAST BODY_TYPE PLUMBING
J 2
(-4475 2150);
DISPLAY 1.234043 (-4475 2150);
PAINT GREEN (-4475 2150);
DISPLAY INVISIBLE (-4475 2150);
FORCEPROP 1 LAST HDL_TAP TRUE
J 2
(-4800 2075);
DISPLAY 1.234043 (-4800 2075);
PAINT GREEN (-4800 2075);
DISPLAY INVISIBLE (-4800 2075);
FORCEPROP 1 LAST PATH I72
J 2
(-4473 2200);
DISPLAY 0.872340 (-4473 2200);
PAINT GREEN (-4473 2200);
DISPLAY INVISIBLE (-4473 2200);
FORCEADD TAP..6
R 2
(-4475 2300);
FORCEPROP 3 LASTPIN (-4525 2300) SIG_NAME M_H_DQ<22>
J 0
(-4515 2310);
DISPLAY 0.659574 (-4515 2310);
PAINT MONO (-4515 2310);
DISPLAY INVISIBLE (-4515 2310);
FORCEPROP 1 LASTPIN (-4525 2300) BN 22
J 2
(-4475 2310);
DISPLAY 0.617021 (-4475 2310);
PAINT PINK (-4475 2310);
FORCEPROP 2 LAST CDS_LIB mstr_standard
J 2
(-4475 2300);
DISPLAY 0.787234 (-4475 2300);
PAINT MONO (-4475 2300);
DISPLAY INVISIBLE (-4475 2300);
FORCEPROP 1 LAST BODY_TYPE PLUMBING
J 2
(-4475 2250);
DISPLAY 1.234043 (-4475 2250);
PAINT GREEN (-4475 2250);
DISPLAY INVISIBLE (-4475 2250);
FORCEPROP 1 LAST HDL_TAP TRUE
J 2
(-4800 2175);
DISPLAY 1.234043 (-4800 2175);
PAINT GREEN (-4800 2175);
DISPLAY INVISIBLE (-4800 2175);
FORCEPROP 1 LAST PATH I73
J 2
(-4473 2300);
DISPLAY 0.872340 (-4473 2300);
PAINT GREEN (-4473 2300);
DISPLAY INVISIBLE (-4473 2300);
FORCEADD TAP..6
R 2
(-4475 2350);
FORCEPROP 3 LASTPIN (-4525 2350) SIG_NAME M_H_DQ<23>
J 0
(-4515 2360);
DISPLAY 0.659574 (-4515 2360);
PAINT MONO (-4515 2360);
DISPLAY INVISIBLE (-4515 2360);
FORCEPROP 1 LASTPIN (-4525 2350) BN 23
J 2
(-4475 2360);
DISPLAY 0.617021 (-4475 2360);
PAINT PINK (-4475 2360);
FORCEPROP 2 LAST CDS_LIB mstr_standard
J 2
(-4475 2350);
DISPLAY 0.787234 (-4475 2350);
PAINT MONO (-4475 2350);
DISPLAY INVISIBLE (-4475 2350);
FORCEPROP 1 LAST BODY_TYPE PLUMBING
J 2
(-4475 2300);
DISPLAY 1.234043 (-4475 2300);
PAINT GREEN (-4475 2300);
DISPLAY INVISIBLE (-4475 2300);
FORCEPROP 1 LAST HDL_TAP TRUE
J 2
(-4800 2225);
DISPLAY 1.234043 (-4800 2225);
PAINT GREEN (-4800 2225);
DISPLAY INVISIBLE (-4800 2225);
FORCEPROP 1 LAST PATH I74
J 2
(-4473 2350);
DISPLAY 0.872340 (-4473 2350);
PAINT GREEN (-4473 2350);
DISPLAY INVISIBLE (-4473 2350);
FORCEADD TAP..6
R 2
(-4475 2500);
FORCEPROP 3 LASTPIN (-4525 2500) SIG_NAME M_H_DQ<26>
J 0
(-4515 2510);
DISPLAY 0.659574 (-4515 2510);
PAINT MONO (-4515 2510);
DISPLAY INVISIBLE (-4515 2510);
FORCEPROP 1 LASTPIN (-4525 2500) BN 26
J 2
(-4475 2510);
DISPLAY 0.617021 (-4475 2510);
PAINT PINK (-4475 2510);
FORCEPROP 2 LAST CDS_LIB mstr_standard
J 2
(-4475 2500);
DISPLAY 0.787234 (-4475 2500);
PAINT MONO (-4475 2500);
DISPLAY INVISIBLE (-4475 2500);
FORCEPROP 1 LAST BODY_TYPE PLUMBING
J 2
(-4475 2450);
DISPLAY 1.234043 (-4475 2450);
PAINT GREEN (-4475 2450);
DISPLAY INVISIBLE (-4475 2450);
FORCEPROP 1 LAST HDL_TAP TRUE
J 2
(-4800 2375);
DISPLAY 1.234043 (-4800 2375);
PAINT GREEN (-4800 2375);
DISPLAY INVISIBLE (-4800 2375);
FORCEPROP 1 LAST PATH I75
J 2
(-4473 2500);
DISPLAY 0.872340 (-4473 2500);
PAINT GREEN (-4473 2500);
DISPLAY INVISIBLE (-4473 2500);
FORCEADD TAP..6
R 2
(-4475 2450);
FORCEPROP 3 LASTPIN (-4525 2450) SIG_NAME M_H_DQ<25>
J 0
(-4515 2460);
DISPLAY 0.659574 (-4515 2460);
PAINT MONO (-4515 2460);
DISPLAY INVISIBLE (-4515 2460);
FORCEPROP 1 LASTPIN (-4525 2450) BN 25
J 2
(-4475 2460);
DISPLAY 0.617021 (-4475 2460);
PAINT PINK (-4475 2460);
FORCEPROP 2 LAST CDS_LIB mstr_standard
J 2
(-4475 2450);
DISPLAY 0.787234 (-4475 2450);
PAINT MONO (-4475 2450);
DISPLAY INVISIBLE (-4475 2450);
FORCEPROP 1 LAST BODY_TYPE PLUMBING
J 2
(-4475 2400);
DISPLAY 1.234043 (-4475 2400);
PAINT GREEN (-4475 2400);
DISPLAY INVISIBLE (-4475 2400);
FORCEPROP 1 LAST HDL_TAP TRUE
J 2
(-4800 2325);
DISPLAY 1.234043 (-4800 2325);
PAINT GREEN (-4800 2325);
DISPLAY INVISIBLE (-4800 2325);
FORCEPROP 1 LAST PATH I76
J 2
(-4473 2450);
DISPLAY 0.872340 (-4473 2450);
PAINT GREEN (-4473 2450);
DISPLAY INVISIBLE (-4473 2450);
FORCEADD TAP..6
R 2
(-4475 2400);
FORCEPROP 3 LASTPIN (-4525 2400) SIG_NAME M_H_DQ<24>
J 0
(-4515 2410);
DISPLAY 0.659574 (-4515 2410);
PAINT MONO (-4515 2410);
DISPLAY INVISIBLE (-4515 2410);
FORCEPROP 1 LASTPIN (-4525 2400) BN 24
J 2
(-4475 2410);
DISPLAY 0.617021 (-4475 2410);
PAINT PINK (-4475 2410);
FORCEPROP 2 LAST CDS_LIB mstr_standard
J 2
(-4475 2400);
DISPLAY 0.787234 (-4475 2400);
PAINT MONO (-4475 2400);
DISPLAY INVISIBLE (-4475 2400);
FORCEPROP 1 LAST BODY_TYPE PLUMBING
J 2
(-4475 2350);
DISPLAY 1.234043 (-4475 2350);
PAINT GREEN (-4475 2350);
DISPLAY INVISIBLE (-4475 2350);
FORCEPROP 1 LAST HDL_TAP TRUE
J 2
(-4800 2275);
DISPLAY 1.234043 (-4800 2275);
PAINT GREEN (-4800 2275);
DISPLAY INVISIBLE (-4800 2275);
FORCEPROP 1 LAST PATH I77
J 2
(-4473 2400);
DISPLAY 0.872340 (-4473 2400);
PAINT GREEN (-4473 2400);
DISPLAY INVISIBLE (-4473 2400);
FORCEADD PVDDQ_GHJ..1
(-4175 1975);
FORCEPROP 3 LASTPIN (-4175 1925) SIG_NAME PVDDQ_GHJ\g
J 0
(-4165 1935);
DISPLAY 0.659574 (-4165 1935);
PAINT MONO (-4165 1935);
DISPLAY INVISIBLE (-4165 1935);
FORCEPROP 1 LAST VOLTAGE 1.2V
J 0
(-4220 1932);
DISPLAY 0.340426 (-4220 1932);
PAINT SKYBLUE (-4220 1932);
DISPLAY INVISIBLE (-4220 1932);
FORCEPROP 2 LAST BOM_COST MEM
J 0
(-4175 1980);
PAINT ORANGE (-4175 1980);
DISPLAY INVISIBLE (-4175 1980);
FORCEPROP 2 LAST CDS_LIB mstr_symbols
J 0
(-4175 1975);
PAINT ORANGE (-4175 1975);
DISPLAY INVISIBLE (-4175 1975);
FORCEPROP 1 LAST BODY_TYPE PLUMBING
J 0
(-4220 1932);
DISPLAY 0.340426 (-4220 1932);
PAINT GREEN (-4220 1932);
DISPLAY INVISIBLE (-4220 1932);
FORCEPROP 1 LAST PATH I78
J 0
(-4125 2000);
DISPLAY 0.872340 (-4125 2000);
PAINT AQUA (-4125 2000);
DISPLAY INVISIBLE (-4125 2000);
FORCEPROP 2 LAST ROOM DDR4_GH_G
J 0
(-4175 2075);
DISPLAY 0.787234 (-4175 2075);
PAINT ORANGE (-4175 2075);
DISPLAY INVISIBLE (-4175 2075);
FORCEPROP 1 LAST HDL_POWER PVDDQ_GHJ
J 1
(-4175 2025);
DISPLAY 0.872340 (-4175 2025);
PAINT GREEN (-4175 2025);
DISPLAY INVISIBLE (-4175 2025);
FORCEADD PVTT_GHJ..1
(-3925 2150);
FORCEPROP 3 LASTPIN (-3925 2100) SIG_NAME PVTT_GHJ\g
J 0
(-3915 2110);
DISPLAY 0.659574 (-3915 2110);
PAINT MONO (-3915 2110);
DISPLAY INVISIBLE (-3915 2110);
FORCEPROP 1 LAST VOLTAGE 0.6V
J 0
(-3970 2107);
DISPLAY 0.340426 (-3970 2107);
PAINT SKYBLUE (-3970 2107);
DISPLAY INVISIBLE (-3970 2107);
FORCEPROP 2 LAST BOM_COST MEM
J 0
(-3925 2155);
PAINT ORANGE (-3925 2155);
DISPLAY INVISIBLE (-3925 2155);
FORCEPROP 2 LAST CDS_LIB mstr_symbols
J 0
(-3925 2150);
PAINT ORANGE (-3925 2150);
DISPLAY INVISIBLE (-3925 2150);
FORCEPROP 1 LAST BODY_TYPE PLUMBING
J 0
(-3970 2107);
DISPLAY 0.340426 (-3970 2107);
PAINT GREEN (-3970 2107);
DISPLAY INVISIBLE (-3970 2107);
FORCEPROP 1 LAST PATH I79
J 0
(-3875 2175);
DISPLAY 0.872340 (-3875 2175);
PAINT AQUA (-3875 2175);
DISPLAY INVISIBLE (-3875 2175);
FORCEPROP 2 LAST ROOM DDR4_GH_G
J 0
(-3925 2250);
DISPLAY 0.787234 (-3925 2250);
PAINT ORANGE (-3925 2250);
DISPLAY INVISIBLE (-3925 2250);
FORCEPROP 1 LAST HDL_POWER PVTT_GHJ
J 1
(-3925 2200);
DISPLAY 0.872340 (-3925 2200);
PAINT GREEN (-3925 2200);
DISPLAY INVISIBLE (-3925 2200);
FORCEADD PVPP_GHJ..1
(-7825 1700);
FORCEPROP 3 LASTPIN (-7825 1650) SIG_NAME PVPP_GHJ\g
J 0
(-7815 1660);
DISPLAY 0.659574 (-7815 1660);
PAINT MONO (-7815 1660);
DISPLAY INVISIBLE (-7815 1660);
FORCEPROP 1 LAST VOLTAGE 2.5V
J 0
(-7870 1657);
DISPLAY 0.340426 (-7870 1657);
PAINT SKYBLUE (-7870 1657);
DISPLAY INVISIBLE (-7870 1657);
FORCEPROP 0 LAST BOM_COST MEM
J 0
(-7825 1800);
PAINT ORANGE (-7825 1800);
DISPLAY INVISIBLE (-7825 1800);
FORCEPROP 2 LAST CDS_LIB mstr_symbols
J 0
(-7825 1700);
PAINT ORANGE (-7825 1700);
DISPLAY INVISIBLE (-7825 1700);
FORCEPROP 1 LAST BODY_TYPE PLUMBING
J 0
(-7870 1657);
DISPLAY 0.340426 (-7870 1657);
PAINT GREEN (-7870 1657);
DISPLAY INVISIBLE (-7870 1657);
FORCEPROP 1 LAST PATH I8
J 0
(-7775 1725);
DISPLAY 0.872340 (-7775 1725);
PAINT AQUA (-7775 1725);
DISPLAY INVISIBLE (-7775 1725);
FORCEPROP 2 LAST ROOM DDR4_GH_G
J 0
(-7825 1800);
PAINT ORANGE (-7825 1800);
DISPLAY INVISIBLE (-7825 1800);
FORCEPROP 1 LAST HDL_POWER PVPP_GHJ
J 1
(-7825 1750);
DISPLAY 0.872340 (-7825 1750);
PAINT GREEN (-7825 1750);
DISPLAY INVISIBLE (-7825 1750);
FORCEADD PVPP_GHJ..1
(-3775 2450);
FORCEPROP 3 LASTPIN (-3775 2400) SIG_NAME PVPP_GHJ\g
J 0
(-3765 2410);
DISPLAY 0.659574 (-3765 2410);
PAINT MONO (-3765 2410);
DISPLAY INVISIBLE (-3765 2410);
FORCEPROP 1 LAST VOLTAGE 2.5V
J 0
(-3820 2407);
DISPLAY 0.340426 (-3820 2407);
PAINT SKYBLUE (-3820 2407);
DISPLAY INVISIBLE (-3820 2407);
FORCEPROP 0 LAST BOM_COST MEM
J 0
(-3775 2550);
PAINT ORANGE (-3775 2550);
DISPLAY INVISIBLE (-3775 2550);
FORCEPROP 2 LAST CDS_LIB mstr_symbols
J 0
(-3775 2450);
PAINT ORANGE (-3775 2450);
DISPLAY INVISIBLE (-3775 2450);
FORCEPROP 1 LAST BODY_TYPE PLUMBING
J 0
(-3820 2407);
DISPLAY 0.340426 (-3820 2407);
PAINT GREEN (-3820 2407);
DISPLAY INVISIBLE (-3820 2407);
FORCEPROP 1 LAST PATH I80
J 0
(-3725 2475);
DISPLAY 0.872340 (-3725 2475);
PAINT AQUA (-3725 2475);
DISPLAY INVISIBLE (-3725 2475);
FORCEPROP 2 LAST ROOM DDR4_GH_G
J 0
(-3775 2550);
PAINT ORANGE (-3775 2550);
DISPLAY INVISIBLE (-3775 2550);
FORCEPROP 1 LAST HDL_POWER PVPP_GHJ
J 1
(-3775 2500);
DISPLAY 0.872340 (-3775 2500);
PAINT GREEN (-3775 2500);
DISPLAY INVISIBLE (-3775 2500);
FORCEADD TAP..6
R 2
(-4475 2550);
FORCEPROP 3 LASTPIN (-4525 2550) SIG_NAME M_H_DQ<27>
J 0
(-4515 2560);
DISPLAY 0.659574 (-4515 2560);
PAINT MONO (-4515 2560);
DISPLAY INVISIBLE (-4515 2560);
FORCEPROP 1 LASTPIN (-4525 2550) BN 27
J 2
(-4475 2560);
DISPLAY 0.617021 (-4475 2560);
PAINT PINK (-4475 2560);
FORCEPROP 2 LAST CDS_LIB mstr_standard
J 2
(-4475 2550);
DISPLAY 0.787234 (-4475 2550);
PAINT MONO (-4475 2550);
DISPLAY INVISIBLE (-4475 2550);
FORCEPROP 1 LAST BODY_TYPE PLUMBING
J 2
(-4475 2500);
DISPLAY 1.234043 (-4475 2500);
PAINT GREEN (-4475 2500);
DISPLAY INVISIBLE (-4475 2500);
FORCEPROP 1 LAST HDL_TAP TRUE
J 2
(-4800 2425);
DISPLAY 1.234043 (-4800 2425);
PAINT GREEN (-4800 2425);
DISPLAY INVISIBLE (-4800 2425);
FORCEPROP 1 LAST PATH I81
J 2
(-4473 2550);
DISPLAY 0.872340 (-4473 2550);
PAINT GREEN (-4473 2550);
DISPLAY INVISIBLE (-4473 2550);
FORCEADD TAP..6
R 2
(-4475 2600);
FORCEPROP 3 LASTPIN (-4525 2600) SIG_NAME M_H_DQ<28>
J 0
(-4515 2610);
DISPLAY 0.659574 (-4515 2610);
PAINT MONO (-4515 2610);
DISPLAY INVISIBLE (-4515 2610);
FORCEPROP 1 LASTPIN (-4525 2600) BN 28
J 2
(-4475 2610);
DISPLAY 0.617021 (-4475 2610);
PAINT PINK (-4475 2610);
FORCEPROP 2 LAST CDS_LIB mstr_standard
J 2
(-4475 2600);
DISPLAY 0.787234 (-4475 2600);
PAINT MONO (-4475 2600);
DISPLAY INVISIBLE (-4475 2600);
FORCEPROP 1 LAST BODY_TYPE PLUMBING
J 2
(-4475 2550);
DISPLAY 1.234043 (-4475 2550);
PAINT GREEN (-4475 2550);
DISPLAY INVISIBLE (-4475 2550);
FORCEPROP 1 LAST HDL_TAP TRUE
J 2
(-4800 2475);
DISPLAY 1.234043 (-4800 2475);
PAINT GREEN (-4800 2475);
DISPLAY INVISIBLE (-4800 2475);
FORCEPROP 1 LAST PATH I82
J 2
(-4473 2600);
DISPLAY 0.872340 (-4473 2600);
PAINT GREEN (-4473 2600);
DISPLAY INVISIBLE (-4473 2600);
FORCEADD TAP..6
R 2
(-4475 2650);
FORCEPROP 3 LASTPIN (-4525 2650) SIG_NAME M_H_DQ<29>
J 0
(-4515 2660);
DISPLAY 0.659574 (-4515 2660);
PAINT MONO (-4515 2660);
DISPLAY INVISIBLE (-4515 2660);
FORCEPROP 1 LASTPIN (-4525 2650) BN 29
J 2
(-4475 2660);
DISPLAY 0.617021 (-4475 2660);
PAINT PINK (-4475 2660);
FORCEPROP 2 LAST CDS_LIB mstr_standard
J 2
(-4475 2650);
DISPLAY 0.787234 (-4475 2650);
PAINT MONO (-4475 2650);
DISPLAY INVISIBLE (-4475 2650);
FORCEPROP 1 LAST BODY_TYPE PLUMBING
J 2
(-4475 2600);
DISPLAY 1.234043 (-4475 2600);
PAINT GREEN (-4475 2600);
DISPLAY INVISIBLE (-4475 2600);
FORCEPROP 1 LAST HDL_TAP TRUE
J 2
(-4800 2525);
DISPLAY 1.234043 (-4800 2525);
PAINT GREEN (-4800 2525);
DISPLAY INVISIBLE (-4800 2525);
FORCEPROP 1 LAST PATH I83
J 2
(-4473 2650);
DISPLAY 0.872340 (-4473 2650);
PAINT GREEN (-4473 2650);
DISPLAY INVISIBLE (-4473 2650);
FORCEADD TAP..6
R 2
(-4475 2750);
FORCEPROP 3 LASTPIN (-4525 2750) SIG_NAME M_H_DQ<31>
J 0
(-4515 2760);
DISPLAY 0.659574 (-4515 2760);
PAINT MONO (-4515 2760);
DISPLAY INVISIBLE (-4515 2760);
FORCEPROP 1 LASTPIN (-4525 2750) BN 31
J 2
(-4475 2760);
DISPLAY 0.617021 (-4475 2760);
PAINT PINK (-4475 2760);
FORCEPROP 2 LAST CDS_LIB mstr_standard
J 2
(-4475 2750);
DISPLAY 0.787234 (-4475 2750);
PAINT MONO (-4475 2750);
DISPLAY INVISIBLE (-4475 2750);
FORCEPROP 1 LAST BODY_TYPE PLUMBING
J 2
(-4475 2700);
DISPLAY 1.234043 (-4475 2700);
PAINT GREEN (-4475 2700);
DISPLAY INVISIBLE (-4475 2700);
FORCEPROP 1 LAST HDL_TAP TRUE
J 2
(-4800 2625);
DISPLAY 1.234043 (-4800 2625);
PAINT GREEN (-4800 2625);
DISPLAY INVISIBLE (-4800 2625);
FORCEPROP 1 LAST PATH I84
J 2
(-4473 2750);
DISPLAY 0.872340 (-4473 2750);
PAINT GREEN (-4473 2750);
DISPLAY INVISIBLE (-4473 2750);
FORCEADD TAP..6
R 2
(-4475 2700);
FORCEPROP 3 LASTPIN (-4525 2700) SIG_NAME M_H_DQ<30>
J 0
(-4515 2710);
DISPLAY 0.659574 (-4515 2710);
PAINT MONO (-4515 2710);
DISPLAY INVISIBLE (-4515 2710);
FORCEPROP 1 LASTPIN (-4525 2700) BN 30
J 2
(-4475 2710);
DISPLAY 0.617021 (-4475 2710);
PAINT PINK (-4475 2710);
FORCEPROP 2 LAST CDS_LIB mstr_standard
J 2
(-4475 2700);
DISPLAY 0.787234 (-4475 2700);
PAINT MONO (-4475 2700);
DISPLAY INVISIBLE (-4475 2700);
FORCEPROP 1 LAST BODY_TYPE PLUMBING
J 2
(-4475 2650);
DISPLAY 1.234043 (-4475 2650);
PAINT GREEN (-4475 2650);
DISPLAY INVISIBLE (-4475 2650);
FORCEPROP 1 LAST HDL_TAP TRUE
J 2
(-4800 2575);
DISPLAY 1.234043 (-4800 2575);
PAINT GREEN (-4800 2575);
DISPLAY INVISIBLE (-4800 2575);
FORCEPROP 1 LAST PATH I85
J 2
(-4473 2700);
DISPLAY 0.872340 (-4473 2700);
PAINT GREEN (-4473 2700);
DISPLAY INVISIBLE (-4473 2700);
FORCEADD TAP..6
R 2
(-4475 2850);
FORCEPROP 3 LASTPIN (-4525 2850) SIG_NAME M_H_DQ<33>
J 0
(-4515 2860);
DISPLAY 0.659574 (-4515 2860);
PAINT MONO (-4515 2860);
DISPLAY INVISIBLE (-4515 2860);
FORCEPROP 1 LASTPIN (-4525 2850) BN 33
J 2
(-4475 2860);
DISPLAY 0.617021 (-4475 2860);
PAINT PINK (-4475 2860);
FORCEPROP 2 LAST CDS_LIB mstr_standard
J 2
(-4475 2850);
DISPLAY 0.787234 (-4475 2850);
PAINT MONO (-4475 2850);
DISPLAY INVISIBLE (-4475 2850);
FORCEPROP 1 LAST BODY_TYPE PLUMBING
J 2
(-4475 2800);
DISPLAY 1.234043 (-4475 2800);
PAINT GREEN (-4475 2800);
DISPLAY INVISIBLE (-4475 2800);
FORCEPROP 1 LAST HDL_TAP TRUE
J 2
(-4800 2725);
DISPLAY 1.234043 (-4800 2725);
PAINT GREEN (-4800 2725);
DISPLAY INVISIBLE (-4800 2725);
FORCEPROP 1 LAST PATH I86
J 2
(-4473 2850);
DISPLAY 0.872340 (-4473 2850);
PAINT GREEN (-4473 2850);
DISPLAY INVISIBLE (-4473 2850);
FORCEADD TAP..6
R 2
(-4475 2800);
FORCEPROP 3 LASTPIN (-4525 2800) SIG_NAME M_H_DQ<32>
J 0
(-4515 2810);
DISPLAY 0.659574 (-4515 2810);
PAINT MONO (-4515 2810);
DISPLAY INVISIBLE (-4515 2810);
FORCEPROP 1 LASTPIN (-4525 2800) BN 32
J 2
(-4475 2810);
DISPLAY 0.617021 (-4475 2810);
PAINT PINK (-4475 2810);
FORCEPROP 2 LAST CDS_LIB mstr_standard
J 2
(-4475 2800);
DISPLAY 0.787234 (-4475 2800);
PAINT MONO (-4475 2800);
DISPLAY INVISIBLE (-4475 2800);
FORCEPROP 1 LAST BODY_TYPE PLUMBING
J 2
(-4475 2750);
DISPLAY 1.234043 (-4475 2750);
PAINT GREEN (-4475 2750);
DISPLAY INVISIBLE (-4475 2750);
FORCEPROP 1 LAST HDL_TAP TRUE
J 2
(-4800 2675);
DISPLAY 1.234043 (-4800 2675);
PAINT GREEN (-4800 2675);
DISPLAY INVISIBLE (-4800 2675);
FORCEPROP 1 LAST PATH I87
J 2
(-4473 2800);
DISPLAY 0.872340 (-4473 2800);
PAINT GREEN (-4473 2800);
DISPLAY INVISIBLE (-4473 2800);
FORCEADD TAP..6
R 2
(-4475 2900);
FORCEPROP 3 LASTPIN (-4525 2900) SIG_NAME M_H_DQ<34>
J 0
(-4515 2910);
DISPLAY 0.659574 (-4515 2910);
PAINT MONO (-4515 2910);
DISPLAY INVISIBLE (-4515 2910);
FORCEPROP 1 LASTPIN (-4525 2900) BN 34
J 2
(-4475 2910);
DISPLAY 0.617021 (-4475 2910);
PAINT PINK (-4475 2910);
FORCEPROP 2 LAST CDS_LIB mstr_standard
J 2
(-4475 2900);
DISPLAY 0.787234 (-4475 2900);
PAINT MONO (-4475 2900);
DISPLAY INVISIBLE (-4475 2900);
FORCEPROP 1 LAST BODY_TYPE PLUMBING
J 2
(-4475 2850);
DISPLAY 1.234043 (-4475 2850);
PAINT GREEN (-4475 2850);
DISPLAY INVISIBLE (-4475 2850);
FORCEPROP 1 LAST HDL_TAP TRUE
J 2
(-4800 2775);
DISPLAY 1.234043 (-4800 2775);
PAINT GREEN (-4800 2775);
DISPLAY INVISIBLE (-4800 2775);
FORCEPROP 1 LAST PATH I88
J 2
(-4473 2900);
DISPLAY 0.872340 (-4473 2900);
PAINT GREEN (-4473 2900);
DISPLAY INVISIBLE (-4473 2900);
FORCEADD TAP..6
R 2
(-4475 3000);
FORCEPROP 3 LASTPIN (-4525 3000) SIG_NAME M_H_DQ<36>
J 0
(-4515 3010);
DISPLAY 0.659574 (-4515 3010);
PAINT MONO (-4515 3010);
DISPLAY INVISIBLE (-4515 3010);
FORCEPROP 1 LASTPIN (-4525 3000) BN 36
J 2
(-4475 3010);
DISPLAY 0.617021 (-4475 3010);
PAINT PINK (-4475 3010);
FORCEPROP 2 LAST CDS_LIB mstr_standard
J 2
(-4475 3000);
DISPLAY 0.787234 (-4475 3000);
PAINT MONO (-4475 3000);
DISPLAY INVISIBLE (-4475 3000);
FORCEPROP 1 LAST BODY_TYPE PLUMBING
J 2
(-4475 2950);
DISPLAY 1.234043 (-4475 2950);
PAINT GREEN (-4475 2950);
DISPLAY INVISIBLE (-4475 2950);
FORCEPROP 1 LAST HDL_TAP TRUE
J 2
(-4800 2875);
DISPLAY 1.234043 (-4800 2875);
PAINT GREEN (-4800 2875);
DISPLAY INVISIBLE (-4800 2875);
FORCEPROP 1 LAST PATH I89
J 2
(-4473 3000);
DISPLAY 0.872340 (-4473 3000);
PAINT GREEN (-4473 3000);
DISPLAY INVISIBLE (-4473 3000);
FORCEADD OFFPAGE..5
(-6650 1700);
FORCEPROP 2 LAST $XR0 79 
J 0
(-6874 1700);
DISPLAY 0.638298 (-6874 1700);
PAINT MONO (-6874 1700);
FORCEPROP 2 LAST $XR1 58 
J 0
(-6964 1700);
DISPLAY 0.638298 (-6964 1700);
PAINT MONO (-6964 1700);
FORCEPROP 2 LAST CDS_LIB mstr_standard
J 0
(-6650 1700);
DISPLAY 0.787234 (-6650 1700);
PAINT MONO (-6650 1700);
DISPLAY INVISIBLE (-6650 1700);
FORCEPROP 1 LAST OFFPAGE TRUE
J 0
(-6325 1575);
DISPLAY 1.404255 (-6325 1575);
PAINT GREEN (-6325 1575);
DISPLAY INVISIBLE (-6325 1575);
FORCEPROP 1 LAST COMMENT_BODY TRUE
J 0
(-6550 1625);
DISPLAY 1.404255 (-6550 1625);
PAINT GREEN (-6550 1625);
DISPLAY INVISIBLE (-6550 1625);
FORCEPROP 2 LAST PATH I9
J 0
(-6850 1750);
DISPLAY 1.021277 (-6850 1750);
PAINT ORANGE (-6850 1750);
DISPLAY INVISIBLE (-6850 1750);
FORCEADD TAP..6
R 2
(-4475 2950);
FORCEPROP 3 LASTPIN (-4525 2950) SIG_NAME M_H_DQ<35>
J 0
(-4515 2960);
DISPLAY 0.659574 (-4515 2960);
PAINT MONO (-4515 2960);
DISPLAY INVISIBLE (-4515 2960);
FORCEPROP 1 LASTPIN (-4525 2950) BN 35
J 2
(-4475 2960);
DISPLAY 0.617021 (-4475 2960);
PAINT PINK (-4475 2960);
FORCEPROP 2 LAST CDS_LIB mstr_standard
J 2
(-4475 2950);
DISPLAY 0.787234 (-4475 2950);
PAINT MONO (-4475 2950);
DISPLAY INVISIBLE (-4475 2950);
FORCEPROP 1 LAST BODY_TYPE PLUMBING
J 2
(-4475 2900);
DISPLAY 1.234043 (-4475 2900);
PAINT GREEN (-4475 2900);
DISPLAY INVISIBLE (-4475 2900);
FORCEPROP 1 LAST HDL_TAP TRUE
J 2
(-4800 2825);
DISPLAY 1.234043 (-4800 2825);
PAINT GREEN (-4800 2825);
DISPLAY INVISIBLE (-4800 2825);
FORCEPROP 1 LAST PATH I90
J 2
(-4473 2950);
DISPLAY 0.872340 (-4473 2950);
PAINT GREEN (-4473 2950);
DISPLAY INVISIBLE (-4473 2950);
FORCEADD TAP..6
R 2
(-4475 3100);
FORCEPROP 3 LASTPIN (-4525 3100) SIG_NAME M_H_DQ<38>
J 0
(-4515 3110);
DISPLAY 0.659574 (-4515 3110);
PAINT MONO (-4515 3110);
DISPLAY INVISIBLE (-4515 3110);
FORCEPROP 1 LASTPIN (-4525 3100) BN 38
J 2
(-4475 3110);
DISPLAY 0.617021 (-4475 3110);
PAINT PINK (-4475 3110);
FORCEPROP 2 LAST CDS_LIB mstr_standard
J 2
(-4475 3100);
DISPLAY 0.787234 (-4475 3100);
PAINT MONO (-4475 3100);
DISPLAY INVISIBLE (-4475 3100);
FORCEPROP 1 LAST BODY_TYPE PLUMBING
J 2
(-4475 3050);
DISPLAY 1.234043 (-4475 3050);
PAINT GREEN (-4475 3050);
DISPLAY INVISIBLE (-4475 3050);
FORCEPROP 1 LAST HDL_TAP TRUE
J 2
(-4800 2975);
DISPLAY 1.234043 (-4800 2975);
PAINT GREEN (-4800 2975);
DISPLAY INVISIBLE (-4800 2975);
FORCEPROP 1 LAST PATH I91
J 2
(-4473 3100);
DISPLAY 0.872340 (-4473 3100);
PAINT GREEN (-4473 3100);
DISPLAY INVISIBLE (-4473 3100);
FORCEADD TAP..6
R 2
(-4475 3050);
FORCEPROP 3 LASTPIN (-4525 3050) SIG_NAME M_H_DQ<37>
J 0
(-4515 3060);
DISPLAY 0.659574 (-4515 3060);
PAINT MONO (-4515 3060);
DISPLAY INVISIBLE (-4515 3060);
FORCEPROP 1 LASTPIN (-4525 3050) BN 37
J 2
(-4475 3060);
DISPLAY 0.617021 (-4475 3060);
PAINT PINK (-4475 3060);
FORCEPROP 2 LAST CDS_LIB mstr_standard
J 2
(-4475 3050);
DISPLAY 0.787234 (-4475 3050);
PAINT MONO (-4475 3050);
DISPLAY INVISIBLE (-4475 3050);
FORCEPROP 1 LAST BODY_TYPE PLUMBING
J 2
(-4475 3000);
DISPLAY 1.234043 (-4475 3000);
PAINT GREEN (-4475 3000);
DISPLAY INVISIBLE (-4475 3000);
FORCEPROP 1 LAST HDL_TAP TRUE
J 2
(-4800 2925);
DISPLAY 1.234043 (-4800 2925);
PAINT GREEN (-4800 2925);
DISPLAY INVISIBLE (-4800 2925);
FORCEPROP 1 LAST PATH I92
J 2
(-4473 3050);
DISPLAY 0.872340 (-4473 3050);
PAINT GREEN (-4473 3050);
DISPLAY INVISIBLE (-4473 3050);
FORCEADD TAP..6
R 2
(-4475 3150);
FORCEPROP 3 LASTPIN (-4525 3150) SIG_NAME M_H_DQ<39>
J 0
(-4515 3160);
DISPLAY 0.659574 (-4515 3160);
PAINT MONO (-4515 3160);
DISPLAY INVISIBLE (-4515 3160);
FORCEPROP 1 LASTPIN (-4525 3150) BN 39
J 2
(-4475 3160);
DISPLAY 0.617021 (-4475 3160);
PAINT PINK (-4475 3160);
FORCEPROP 2 LAST CDS_LIB mstr_standard
J 2
(-4475 3150);
DISPLAY 0.787234 (-4475 3150);
PAINT MONO (-4475 3150);
DISPLAY INVISIBLE (-4475 3150);
FORCEPROP 1 LAST BODY_TYPE PLUMBING
J 2
(-4475 3100);
DISPLAY 1.234043 (-4475 3100);
PAINT GREEN (-4475 3100);
DISPLAY INVISIBLE (-4475 3100);
FORCEPROP 1 LAST HDL_TAP TRUE
J 2
(-4800 3025);
DISPLAY 1.234043 (-4800 3025);
PAINT GREEN (-4800 3025);
DISPLAY INVISIBLE (-4800 3025);
FORCEPROP 1 LAST PATH I93
J 2
(-4473 3150);
DISPLAY 0.872340 (-4473 3150);
PAINT GREEN (-4473 3150);
DISPLAY INVISIBLE (-4473 3150);
FORCEADD TAP..6
R 2
(-4475 3250);
FORCEPROP 3 LASTPIN (-4525 3250) SIG_NAME M_H_DQ<41>
J 0
(-4515 3260);
DISPLAY 0.659574 (-4515 3260);
PAINT MONO (-4515 3260);
DISPLAY INVISIBLE (-4515 3260);
FORCEPROP 1 LASTPIN (-4525 3250) BN 41
J 2
(-4475 3260);
DISPLAY 0.617021 (-4475 3260);
PAINT PINK (-4475 3260);
FORCEPROP 2 LAST CDS_LIB mstr_standard
J 2
(-4475 3250);
DISPLAY 0.787234 (-4475 3250);
PAINT MONO (-4475 3250);
DISPLAY INVISIBLE (-4475 3250);
FORCEPROP 1 LAST BODY_TYPE PLUMBING
J 2
(-4475 3200);
DISPLAY 1.234043 (-4475 3200);
PAINT GREEN (-4475 3200);
DISPLAY INVISIBLE (-4475 3200);
FORCEPROP 1 LAST HDL_TAP TRUE
J 2
(-4800 3125);
DISPLAY 1.234043 (-4800 3125);
PAINT GREEN (-4800 3125);
DISPLAY INVISIBLE (-4800 3125);
FORCEPROP 1 LAST PATH I94
J 2
(-4473 3250);
DISPLAY 0.872340 (-4473 3250);
PAINT GREEN (-4473 3250);
DISPLAY INVISIBLE (-4473 3250);
FORCEADD TAP..6
R 2
(-4475 3200);
FORCEPROP 3 LASTPIN (-4525 3200) SIG_NAME M_H_DQ<40>
J 0
(-4515 3210);
DISPLAY 0.659574 (-4515 3210);
PAINT MONO (-4515 3210);
DISPLAY INVISIBLE (-4515 3210);
FORCEPROP 1 LASTPIN (-4525 3200) BN 40
J 2
(-4475 3210);
DISPLAY 0.617021 (-4475 3210);
PAINT PINK (-4475 3210);
FORCEPROP 2 LAST CDS_LIB mstr_standard
J 2
(-4475 3200);
DISPLAY 0.787234 (-4475 3200);
PAINT MONO (-4475 3200);
DISPLAY INVISIBLE (-4475 3200);
FORCEPROP 1 LAST BODY_TYPE PLUMBING
J 2
(-4475 3150);
DISPLAY 1.234043 (-4475 3150);
PAINT GREEN (-4475 3150);
DISPLAY INVISIBLE (-4475 3150);
FORCEPROP 1 LAST HDL_TAP TRUE
J 2
(-4800 3075);
DISPLAY 1.234043 (-4800 3075);
PAINT GREEN (-4800 3075);
DISPLAY INVISIBLE (-4800 3075);
FORCEPROP 1 LAST PATH I95
J 2
(-4473 3200);
DISPLAY 0.872340 (-4473 3200);
PAINT GREEN (-4473 3200);
DISPLAY INVISIBLE (-4473 3200);
FORCEADD TAP..6
R 2
(-4475 3350);
FORCEPROP 3 LASTPIN (-4525 3350) SIG_NAME M_H_DQ<43>
J 0
(-4515 3360);
DISPLAY 0.659574 (-4515 3360);
PAINT MONO (-4515 3360);
DISPLAY INVISIBLE (-4515 3360);
FORCEPROP 1 LASTPIN (-4525 3350) BN 43
J 2
(-4475 3360);
DISPLAY 0.617021 (-4475 3360);
PAINT PINK (-4475 3360);
FORCEPROP 2 LAST CDS_LIB mstr_standard
J 2
(-4475 3350);
DISPLAY 0.787234 (-4475 3350);
PAINT MONO (-4475 3350);
DISPLAY INVISIBLE (-4475 3350);
FORCEPROP 1 LAST BODY_TYPE PLUMBING
J 2
(-4475 3300);
DISPLAY 1.234043 (-4475 3300);
PAINT GREEN (-4475 3300);
DISPLAY INVISIBLE (-4475 3300);
FORCEPROP 1 LAST HDL_TAP TRUE
J 2
(-4800 3225);
DISPLAY 1.234043 (-4800 3225);
PAINT GREEN (-4800 3225);
DISPLAY INVISIBLE (-4800 3225);
FORCEPROP 1 LAST PATH I96
J 2
(-4473 3350);
DISPLAY 0.872340 (-4473 3350);
PAINT GREEN (-4473 3350);
DISPLAY INVISIBLE (-4473 3350);
FORCEADD TAP..6
R 2
(-4475 3300);
FORCEPROP 3 LASTPIN (-4525 3300) SIG_NAME M_H_DQ<42>
J 0
(-4515 3310);
DISPLAY 0.659574 (-4515 3310);
PAINT MONO (-4515 3310);
DISPLAY INVISIBLE (-4515 3310);
FORCEPROP 1 LASTPIN (-4525 3300) BN 42
J 2
(-4475 3310);
DISPLAY 0.617021 (-4475 3310);
PAINT PINK (-4475 3310);
FORCEPROP 2 LAST CDS_LIB mstr_standard
J 2
(-4475 3300);
DISPLAY 0.787234 (-4475 3300);
PAINT MONO (-4475 3300);
DISPLAY INVISIBLE (-4475 3300);
FORCEPROP 1 LAST BODY_TYPE PLUMBING
J 2
(-4475 3250);
DISPLAY 1.234043 (-4475 3250);
PAINT GREEN (-4475 3250);
DISPLAY INVISIBLE (-4475 3250);
FORCEPROP 1 LAST HDL_TAP TRUE
J 2
(-4800 3175);
DISPLAY 1.234043 (-4800 3175);
PAINT GREEN (-4800 3175);
DISPLAY INVISIBLE (-4800 3175);
FORCEPROP 1 LAST PATH I97
J 2
(-4473 3300);
DISPLAY 0.872340 (-4473 3300);
PAINT GREEN (-4473 3300);
DISPLAY INVISIBLE (-4473 3300);
FORCEADD TAP..6
R 2
(-4475 3400);
FORCEPROP 3 LASTPIN (-4525 3400) SIG_NAME M_H_DQ<44>
J 0
(-4515 3410);
DISPLAY 0.659574 (-4515 3410);
PAINT MONO (-4515 3410);
DISPLAY INVISIBLE (-4515 3410);
FORCEPROP 1 LASTPIN (-4525 3400) BN 44
J 2
(-4475 3410);
DISPLAY 0.617021 (-4475 3410);
PAINT PINK (-4475 3410);
FORCEPROP 2 LAST CDS_LIB mstr_standard
J 2
(-4475 3400);
DISPLAY 0.787234 (-4475 3400);
PAINT MONO (-4475 3400);
DISPLAY INVISIBLE (-4475 3400);
FORCEPROP 1 LAST BODY_TYPE PLUMBING
J 2
(-4475 3350);
DISPLAY 1.234043 (-4475 3350);
PAINT GREEN (-4475 3350);
DISPLAY INVISIBLE (-4475 3350);
FORCEPROP 1 LAST HDL_TAP TRUE
J 2
(-4800 3275);
DISPLAY 1.234043 (-4800 3275);
PAINT GREEN (-4800 3275);
DISPLAY INVISIBLE (-4800 3275);
FORCEPROP 1 LAST PATH I98
J 2
(-4473 3400);
DISPLAY 0.872340 (-4473 3400);
PAINT GREEN (-4473 3400);
DISPLAY INVISIBLE (-4473 3400);
FORCEADD TAP..6
R 2
(-4475 3500);
FORCEPROP 3 LASTPIN (-4525 3500) SIG_NAME M_H_DQ<46>
J 0
(-4515 3510);
DISPLAY 0.659574 (-4515 3510);
PAINT MONO (-4515 3510);
DISPLAY INVISIBLE (-4515 3510);
FORCEPROP 1 LASTPIN (-4525 3500) BN 46
J 2
(-4475 3510);
DISPLAY 0.617021 (-4475 3510);
PAINT PINK (-4475 3510);
FORCEPROP 2 LAST CDS_LIB mstr_standard
J 2
(-4475 3500);
DISPLAY 0.787234 (-4475 3500);
PAINT MONO (-4475 3500);
DISPLAY INVISIBLE (-4475 3500);
FORCEPROP 1 LAST BODY_TYPE PLUMBING
J 2
(-4475 3450);
DISPLAY 1.234043 (-4475 3450);
PAINT GREEN (-4475 3450);
DISPLAY INVISIBLE (-4475 3450);
FORCEPROP 1 LAST HDL_TAP TRUE
J 2
(-4800 3375);
DISPLAY 1.234043 (-4800 3375);
PAINT GREEN (-4800 3375);
DISPLAY INVISIBLE (-4800 3375);
FORCEPROP 1 LAST PATH I99
J 2
(-4473 3500);
DISPLAY 0.872340 (-4473 3500);
PAINT GREEN (-4473 3500);
DISPLAY INVISIBLE (-4473 3500);
FORCEADD INTEL_CORP_BPAGE..1
(0 0);
FORCEPROP 1 LAST CDS_CON_LAST_MODIFIED Tue Dec 01 11:51:42 2015
J 0
(-1425 325);
PAINT ORANGE (-1425 325);
DISPLAY INVISIBLE (-1425 325);
FORCEPROP 1 LAST CUSTOM_TXT_CDS <CURRENT_DESIGN_SHEET> OF <TOTAL_DESIGN_SHEETS>
J 0
(-500 25);
PAINT GREEN (-500 25);
FORCEPROP 1 LAST CUSTOM_TXT_CDS <CON_LAST_MODIFIED>
J 0
(-1925 350);
PAINT GREEN (-1925 350);
FORCEPROP 2 LAST CUSTOM_TXT_CDS <XR_PAGE_TITLE>
J 0
(-7890 5250);
DISPLAY 0.638298 (-7890 5250);
PAINT PINK (-7890 5250);
DISPLAY INVISIBLE (-7890 5250);
FORCEPROP 1 LAST SCH_ADDRESS3 Santa Clara, CA 95052-8119
J 0
(-3975 25);
DISPLAY 0.617021 (-3975 25);
PAINT GREEN (-3975 25);
FORCEPROP 1 LAST SCH_ADDRESS2 P.O. BOX 58119
J 0
(-3975 75);
DISPLAY 0.617021 (-3975 75);
PAINT GREEN (-3975 75);
FORCEPROP 1 LAST SCH_ADDRESS1 2200 Mission College Blvd.
J 0
(-3975 125);
DISPLAY 0.617021 (-3975 125);
PAINT GREEN (-3975 125);
FORCEPROP 1 LAST SCH_TITLE CPU1 DDR4 CH H DIMM1
J 0
(-7950 50);
DISPLAY 1.212766 (-7950 50);
PAINT ORANGE (-7950 50);
FORCEPROP 1 LAST SCH_NUMBER H4694802
J 0
(-1300 150);
DISPLAY 1.212766 (-1300 150);
PAINT YELLOW (-1300 150);
FORCEPROP 1 LAST SCH_DEPT BESD
J 1
(-4450 100);
DISPLAY 1.212766 (-4450 100);
PAINT YELLOW (-4450 100);
FORCEPROP 1 LAST SCH_REV 2.420
J 0
(-250 150);
DISPLAY 0.978723 (-250 150);
PAINT YELLOW (-250 150);
FORCEPROP 2 LAST CDS_LIB mstr_symbols
J 0
(0 0);
PAINT ORANGE (0 0);
DISPLAY INVISIBLE (0 0);
FORCEPROP 2 LAST PAGE_BORDER TRUE
J 0
(-7890 5250);
DISPLAY 1.042553 (-7890 5250);
PAINT PINK (-7890 5250);
DISPLAY INVISIBLE (-7890 5250);
FORCEPROP 1 LAST COMMENT_BODY TRUE
J 0
(12 12);
DISPLAY 0.489362 (12 12);
PAINT GREEN (12 12);
DISPLAY INVISIBLE (12 12);
FORCEPROP 2 LAST CDS_XR_PAGE_TITLE CR-80 : @BASEBOARD_FAB2_LIB.BASEBOARD_FAB2(SCH_1):PAGE80
J 0
(-7890 5250);
DISPLAY 0.638298 (-7890 5250);
PAINT PINK (-7890 5250);
DISPLAY INVISIBLE (-7890 5250);
FORCEADD BOM_NOTE..1
(-7675 4750);
FORCEPROP 0 LAST L1 UNSTUFF FOR SKU B
J 0
(-7825 4650);
DISPLAY 1.063830 (-7825 4650);
PAINT WHITE (-7825 4650);
FORCEPROP 2 LAST BOM_COST SB
J 0
(-7825 4725);
DISPLAY 1.361702 (-7825 4725);
PAINT ORANGE (-7825 4725);
DISPLAY INVISIBLE (-7825 4725);
FORCEPROP 2 LAST CDS_LIB mstr_symbols
J 0
(-7675 4750);
PAINT ORANGE (-7675 4750);
DISPLAY INVISIBLE (-7675 4750);
FORCEPROP 1 LAST COMMENT_BODY TRUE
J 0
(-7650 4850);
DISPLAY 1.319149 (-7650 4850);
PAINT ORANGE (-7650 4850);
DISPLAY INVISIBLE (-7650 4850);
FORCEPROP 2 LAST ROOM SB_HEADERS
J 0
(-7825 4725);
DISPLAY 1.361702 (-7825 4725);
PAINT ORANGE (-7825 4725);
DISPLAY INVISIBLE (-7825 4725);
WIRE 17 -1 (-1925 4625)(-1925 4650);
WIRE 17 -1 (-1925 4525)(-1925 4625);
WIRE 17 -1 (-1125 4650)(-1925 4650);
FORCEPROP 2 LAST SIG_NAME M_H_DQS_DP<17:0>
J 0
(-1700 4660);
DISPLAY 0.617021 (-1700 4660);
PAINT ORANGE (-1700 4660);
WIRE 17 -1 (-1725 4575)(-1725 4600);
WIRE 17 -1 (-1725 4475)(-1725 4575);
WIRE 17 -1 (-1125 4600)(-1725 4600);
FORCEPROP 2 LAST SIG_NAME M_H_DQS_DN<17:0>
J 0
(-1700 4610);
DISPLAY 0.617021 (-1700 4610);
PAINT ORANGE (-1700 4610);
WIRE 17 -1 (-1925 4425)(-1925 4525);
WIRE 17 -1 (-1725 4375)(-1725 4475);
WIRE 17 -1 (-1925 4325)(-1925 4425);
WIRE 17 -1 (-1925 4225)(-1925 4325);
WIRE 17 -1 (-1925 4125)(-1925 4225);
WIRE 17 -1 (-1725 4275)(-1725 4375);
WIRE 17 -1 (-1725 4175)(-1725 4275);
WIRE 17 -1 (-1725 4075)(-1725 4175);
WIRE 17 -1 (-1925 4025)(-1925 4125);
WIRE 17 -1 (-1725 3975)(-1725 4075);
WIRE 17 -1 (-1925 3925)(-1925 4025);
WIRE 17 -1 (-1925 3825)(-1925 3925);
WIRE 17 -1 (-1925 3725)(-1925 3825);
WIRE 17 -1 (-1725 3875)(-1725 3975);
WIRE 17 -1 (-1725 3775)(-1725 3875);
WIRE 17 -1 (-1725 3675)(-1725 3775);
WIRE 17 -1 (-1925 3625)(-1925 3725);
WIRE 17 -1 (-1925 3525)(-1925 3625);
WIRE 17 -1 (-1925 3425)(-1925 3525);
WIRE 17 -1 (-1925 3325)(-1925 3425);
WIRE 17 -1 (-1925 3225)(-1925 3325);
WIRE 17 -1 (-1925 3125)(-1925 3225);
WIRE 17 -1 (-1925 3025)(-1925 3125);
WIRE 17 -1 (-1925 2925)(-1925 3025);
WIRE 17 -1 (-1725 3575)(-1725 3675);
WIRE 17 -1 (-1725 3475)(-1725 3575);
WIRE 17 -1 (-1725 3375)(-1725 3475);
WIRE 17 -1 (-1725 3275)(-1725 3375);
WIRE 17 -1 (-1725 3175)(-1725 3275);
WIRE 17 -1 (-1725 3075)(-1725 3175);
WIRE 17 -1 (-1725 2975)(-1725 3075);
WIRE 17 -1 (-1725 2875)(-1725 2975);
WIRE 17 -1 (-4425 4375)(-4425 4400);
WIRE 17 -1 (-4425 4325)(-4425 4375);
WIRE 17 -1 (-3925 4400)(-4425 4400);
FORCEPROP 2 LAST SIG_NAME M_H_DQ<63:0>
J 0
(-4385 4410);
DISPLAY 0.617021 (-4385 4410);
PAINT ORANGE (-4385 4410);
WIRE 17 -1 (-4425 4275)(-4425 4325);
WIRE 17 -1 (-4425 4125)(-4425 4175);
WIRE 17 -1 (-4425 4075)(-4425 4125);
WIRE 17 -1 (-4425 4175)(-4425 4225);
WIRE 17 -1 (-4425 4225)(-4425 4275);
WIRE 17 -1 (-4425 4025)(-4425 4075);
WIRE 17 -1 (-4425 3975)(-4425 4025);
WIRE 17 -1 (-4425 3925)(-4425 3975);
WIRE 17 -1 (-4425 3875)(-4425 3925);
WIRE 17 -1 (-6025 4325)(-6025 4375);
WIRE 17 -1 (-6025 4275)(-6025 4325);
WIRE 17 -1 (-6025 4375)(-6025 4400);
WIRE 17 -1 (-6575 4400)(-6025 4400);
FORCEPROP 2 LAST SIG_NAME M_H_MA<17:0>
J 0
(-6525 4410);
DISPLAY 0.617021 (-6525 4410);
PAINT ORANGE (-6525 4410);
WIRE 17 -1 (-6025 4225)(-6025 4275);
WIRE 17 -1 (-6025 4175)(-6025 4225);
WIRE 17 -1 (-6025 4125)(-6025 4175);
WIRE 17 -1 (-6025 4075)(-6025 4125);
WIRE 17 -1 (-6025 4025)(-6025 4075);
WIRE 17 -1 (-6025 3975)(-6025 4025);
WIRE 17 -1 (-6025 3925)(-6025 3975);
WIRE 17 -1 (-6025 3875)(-6025 3925);
WIRE 17 -1 (-4425 3725)(-4425 3775);
WIRE 17 -1 (-4425 3675)(-4425 3725);
WIRE 17 -1 (-4425 3775)(-4425 3825);
WIRE 17 -1 (-4425 3825)(-4425 3875);
WIRE 17 -1 (-4425 3625)(-4425 3675);
WIRE 17 -1 (-4425 3575)(-4425 3625);
WIRE 17 -1 (-4425 3525)(-4425 3575);
WIRE 17 -1 (-4425 3475)(-4425 3525);
WIRE 17 -1 (-4425 3425)(-4425 3475);
WIRE 17 -1 (-4425 3375)(-4425 3425);
WIRE 17 -1 (-4425 3325)(-4425 3375);
WIRE 17 -1 (-4425 3275)(-4425 3325);
WIRE 17 -1 (-4425 3225)(-4425 3275);
WIRE 17 -1 (-4425 3175)(-4425 3225);
WIRE 17 -1 (-4425 3125)(-4425 3175);
WIRE 17 -1 (-4425 3075)(-4425 3125);
WIRE 17 -1 (-4425 3025)(-4425 3075);
WIRE 17 -1 (-4425 2975)(-4425 3025);
WIRE 17 -1 (-4425 2925)(-4425 2975);
WIRE 17 -1 (-4425 2875)(-4425 2925);
WIRE 17 -1 (-4425 2825)(-4425 2875);
WIRE 17 -1 (-4425 2775)(-4425 2825);
WIRE 17 -1 (-4425 2725)(-4425 2775);
WIRE 17 -1 (-4425 2675)(-4425 2725);
WIRE 17 -1 (-4425 2625)(-4425 2675);
WIRE 17 -1 (-4425 2575)(-4425 2625);
WIRE 17 -1 (-4425 2525)(-4425 2575);
WIRE 17 -1 (-4425 2475)(-4425 2525);
WIRE 17 -1 (-4425 2425)(-4425 2475);
WIRE 17 -1 (-4425 2375)(-4425 2425);
WIRE 17 -1 (-4425 2325)(-4425 2375);
WIRE 17 -1 (-4425 2275)(-4425 2325);
WIRE 17 -1 (-4425 2225)(-4425 2275);
WIRE 17 -1 (-4425 2175)(-4425 2225);
WIRE 17 -1 (-4425 2125)(-4425 2175);
WIRE 17 -1 (-4425 2075)(-4425 2125);
WIRE 17 -1 (-4425 2025)(-4425 2075);
WIRE 17 -1 (-4425 1975)(-4425 2025);
WIRE 17 -1 (-4425 1925)(-4425 1975);
WIRE 17 -1 (-4425 1875)(-4425 1925);
WIRE 17 -1 (-4425 1825)(-4425 1875);
WIRE 17 -1 (-4425 1775)(-4425 1825);
WIRE 17 -1 (-4425 1725)(-4425 1775);
WIRE 17 -1 (-4425 1675)(-4425 1725);
WIRE 17 -1 (-4425 1625)(-4425 1675);
WIRE 17 -1 (-4425 1575)(-4425 1625);
WIRE 17 -1 (-4425 1525)(-4425 1575);
WIRE 17 -1 (-4425 1475)(-4425 1525);
WIRE 17 -1 (-4425 1425)(-4425 1475);
WIRE 17 -1 (-4425 1375)(-4425 1425);
WIRE 17 -1 (-4425 1325)(-4425 1375);
WIRE 17 -1 (-4425 1275)(-4425 1325);
WIRE 17 -1 (-4425 1225)(-4425 1275);
WIRE 17 -1 (-6025 3825)(-6025 3875);
WIRE 17 -1 (-6025 3775)(-6025 3825);
WIRE 17 -1 (-6025 3725)(-6025 3775);
WIRE 17 -1 (-6025 3675)(-6025 3725);
WIRE 17 -1 (-6025 3625)(-6025 3675);
WIRE 17 -1 (-6025 3575)(-6025 3625);
WIRE 17 -1 (-6025 3525)(-6025 3575);
WIRE 17 -1 (-6225 3150)(-6225 3125);
WIRE 17 -1 (-6225 3150)(-6575 3150);
FORCEPROP 2 LAST SIG_NAME M_H_CLK_DN<3:0>
J 0
(-6525 3160);
DISPLAY 0.617021 (-6525 3160);
PAINT ORANGE (-6525 3160);
WIRE 17 -1 (-6025 3200)(-6025 3175);
WIRE 17 -1 (-6025 3200)(-6575 3200);
FORCEPROP 2 LAST SIG_NAME M_H_CLK_DP<3:0>
J 0
(-6525 3210);
DISPLAY 0.617021 (-6525 3210);
PAINT ORANGE (-6525 3210);
WIRE 17 -1 (-6025 3375)(-6025 3425);
WIRE 17 -1 (-6025 3450)(-6025 3425);
WIRE 17 -1 (-6025 3450)(-6575 3450);
FORCEPROP 2 LAST SIG_NAME M_H_BA<1:0>
J 0
(-6525 3460);
DISPLAY 0.617021 (-6525 3460);
PAINT ORANGE (-6525 3460);
WIRE 17 -1 (-6025 3350)(-6025 3325);
WIRE 17 -1 (-6025 3350)(-6575 3350);
FORCEPROP 2 LAST SIG_NAME M_H_BG<1:0>
J 0
(-6525 3360);
DISPLAY 0.617021 (-6525 3360);
PAINT ORANGE (-6525 3360);
WIRE 17 -1 (-6025 3275)(-6025 3325);
WIRE 17 -1 (-6225 3125)(-6225 3025);
WIRE 17 -1 (-6025 2725)(-6025 2775);
WIRE 17 -1 (-6025 2775)(-6025 2825);
WIRE 17 -1 (-6025 2825)(-6025 2875);
WIRE 17 -1 (-6025 2900)(-6025 2875);
WIRE 17 -1 (-6025 2900)(-6575 2900);
FORCEPROP 2 LAST SIG_NAME M_H_CS_N<7:0>
J 0
(-6550 2910);
DISPLAY 0.617021 (-6550 2910);
PAINT ORANGE (-6550 2910);
WIRE 17 -1 (-6025 2575)(-6025 2625);
WIRE 17 -1 (-6025 2650)(-6025 2625);
WIRE 17 -1 (-6025 2650)(-6575 2650);
FORCEPROP 2 LAST SIG_NAME M_H_CKE<3:0>
J 0
(-6550 2660);
DISPLAY 0.617021 (-6550 2660);
PAINT ORANGE (-6550 2660);
WIRE 17 -1 (-6025 3075)(-6025 3175);
WIRE 17 -1 (-6025 2500)(-6025 2475);
WIRE 17 -1 (-6025 2500)(-6575 2500);
FORCEPROP 2 LAST SIG_NAME M_H_ODT<3:0>
J 0
(-6550 2510);
DISPLAY 0.617021 (-6550 2510);
PAINT ORANGE (-6550 2510);
WIRE 17 -1 (-6025 2425)(-6025 2475);
WIRE 17 -1 (-6025 2350)(-6025 2325);
WIRE 17 -1 (-6025 2350)(-6575 2350);
FORCEPROP 2 LAST SIG_NAME M_H_ECC<7:0>
J 0
(-6550 2360);
DISPLAY 0.617021 (-6550 2360);
PAINT ORANGE (-6550 2360);
WIRE 17 -1 (-6025 2075)(-6025 2125);
WIRE 17 -1 (-6025 2025)(-6025 2075);
WIRE 17 -1 (-6025 2125)(-6025 2175);
WIRE 17 -1 (-6025 2175)(-6025 2225);
WIRE 17 -1 (-6025 1975)(-6025 2025);
WIRE 17 -1 (-6025 2225)(-6025 2275);
WIRE 17 -1 (-6025 2275)(-6025 2325);
WIRE 16 -1 (-7825 1500)(-5725 1500);
WIRE 16 -1 (-7825 1400)(-7825 1500);
WIRE 16 -1 (-1575 3000)(-1375 3000);
WIRE 16 -1 (-1575 2950)(-1575 3000);
WIRE 16 -1 (-1575 2950)(-1375 2950);
WIRE 16 -1 (-1575 2900)(-1575 2950);
WIRE 16 -1 (-1575 2900)(-1375 2900);
WIRE 16 -1 (-1575 2850)(-1575 2900);
WIRE 16 -1 (-1575 2850)(-1375 2850);
WIRE 16 -1 (-1575 2800)(-1575 2850);
WIRE 16 -1 (-1575 2800)(-1375 2800);
WIRE 16 -1 (-1575 2750)(-1575 2800);
WIRE 16 -1 (-1575 2750)(-1375 2750);
WIRE 16 -1 (-1575 2700)(-1575 2750);
WIRE 16 -1 (-1575 2700)(-1375 2700);
WIRE 16 -1 (-1575 2650)(-1575 2700);
WIRE 16 -1 (-1575 2650)(-1375 2650);
WIRE 16 -1 (-1575 2600)(-1575 2650);
WIRE 16 -1 (-1575 2600)(-1375 2600);
WIRE 16 -1 (-1575 2550)(-1575 2600);
WIRE 16 -1 (-1575 2550)(-1375 2550);
WIRE 16 -1 (-1575 2500)(-1575 2550);
WIRE 16 -1 (-1575 2500)(-1375 2500);
WIRE 16 -1 (-1575 2450)(-1575 2500);
WIRE 16 -1 (-1575 2450)(-1375 2450);
WIRE 16 -1 (-1575 2400)(-1575 2450);
WIRE 16 -1 (-1575 2400)(-1375 2400);
WIRE 16 -1 (-1575 2350)(-1575 2400);
WIRE 16 -1 (-1575 2350)(-1375 2350);
WIRE 16 -1 (-1575 2300)(-1575 2350);
WIRE 16 -1 (-1575 2300)(-1375 2300);
WIRE 16 -1 (-1575 2250)(-1575 2300);
WIRE 16 -1 (-1575 2250)(-1375 2250);
WIRE 16 -1 (-1575 2200)(-1575 2250);
WIRE 16 -1 (-1575 2200)(-1375 2200);
WIRE 16 -1 (-1575 2150)(-1575 2200);
WIRE 16 -1 (-1575 2150)(-1375 2150);
WIRE 16 -1 (-1575 2100)(-1575 2150);
WIRE 16 -1 (-1575 2100)(-1375 2100);
WIRE 16 -1 (-1575 2050)(-1575 2100);
WIRE 16 -1 (-1575 2050)(-1375 2050);
WIRE 16 -1 (-1575 2000)(-1575 2050);
WIRE 16 -1 (-1575 2000)(-1375 2000);
WIRE 16 -1 (-1575 1950)(-1575 2000);
WIRE 16 -1 (-1575 1950)(-1375 1950);
WIRE 16 -1 (-1575 1900)(-1575 1950);
WIRE 16 -1 (-1575 1900)(-1375 1900);
WIRE 16 -1 (-1575 1850)(-1575 1900);
WIRE 16 -1 (-1575 1850)(-1375 1850);
WIRE 16 -1 (-1575 1800)(-1575 1850);
WIRE 16 -1 (-1575 1800)(-1375 1800);
WIRE 16 -1 (-1575 1750)(-1575 1800);
WIRE 16 -1 (-1575 1750)(-1375 1750);
WIRE 16 -1 (-1575 1700)(-1575 1750);
WIRE 16 -1 (-1575 1700)(-1375 1700);
WIRE 16 -1 (-1575 1650)(-1575 1700);
WIRE 16 -1 (-1575 1650)(-1375 1650);
WIRE 16 -1 (-1575 1600)(-1575 1650);
WIRE 16 -1 (-1575 1600)(-1375 1600);
WIRE 16 -1 (-1575 1550)(-1575 1600);
WIRE 16 -1 (-1575 1550)(-1375 1550);
WIRE 16 -1 (-1575 1500)(-1575 1550);
WIRE 16 -1 (-1575 1500)(-1375 1500);
WIRE 16 -1 (-1575 1450)(-1575 1500);
WIRE 16 -1 (-1575 1450)(-1375 1450);
WIRE 16 -1 (-1575 1400)(-1575 1450);
WIRE 16 -1 (-1575 1400)(-1375 1400);
WIRE 16 -1 (-1575 1350)(-1575 1400);
WIRE 16 -1 (-1575 1350)(-1375 1350);
WIRE 16 -1 (-1575 1300)(-1575 1350);
WIRE 16 -1 (-1575 1300)(-1375 1300);
WIRE 16 -1 (-1575 1250)(-1575 1300);
WIRE 16 -1 (-1575 1250)(-1375 1250);
WIRE 16 -1 (-1575 1200)(-1575 1250);
WIRE 16 -1 (-1575 1200)(-1375 1200);
WIRE 16 -1 (-1575 1150)(-1575 1200);
WIRE 16 -1 (-1575 1150)(-1375 1150);
WIRE 16 -1 (-1575 1100)(-1575 1150);
WIRE 16 -1 (-1575 1100)(-1375 1100);
WIRE 16 -1 (-1575 1050)(-1575 1100);
WIRE 16 -1 (-1575 1050)(-1375 1050);
WIRE 16 -1 (-1575 1000)(-1575 1050);
WIRE 16 -1 (-1575 1000)(-1375 1000);
WIRE 16 -1 (-1575 950)(-1575 1000);
WIRE 16 -1 (-1575 950)(-1375 950);
WIRE 16 -1 (-1575 900)(-1575 950);
WIRE 16 -1 (-1575 900)(-1375 900);
WIRE 16 -1 (-1575 850)(-1575 900);
WIRE 16 -1 (-1575 850)(-1375 850);
WIRE 16 -1 (-1575 800)(-1575 850);
WIRE 16 -1 (-1575 800)(-1375 800);
WIRE 16 -1 (-1575 750)(-1575 800);
WIRE 16 -1 (-1575 750)(-1375 750);
WIRE 16 -1 (-1575 700)(-1575 750);
WIRE 16 -1 (-1575 700)(-1375 700);
WIRE 16 -1 (-1575 600)(-1575 700);
WIRE 16 -1 (-175 2950)(-175 3000);
WIRE 16 -1 (-175 2900)(-175 2950);
WIRE 16 -1 (-175 2950)(-375 2950);
WIRE 16 -1 (-175 3000)(-375 3000);
WIRE 16 -1 (-175 2850)(-175 2900);
WIRE 16 -1 (-175 2900)(-375 2900);
WIRE 16 -1 (-175 2800)(-175 2850);
WIRE 16 -1 (-175 2850)(-375 2850);
WIRE 16 -1 (-175 2750)(-175 2800);
WIRE 16 -1 (-175 2800)(-375 2800);
WIRE 16 -1 (-175 2700)(-175 2750);
WIRE 16 -1 (-175 2750)(-375 2750);
WIRE 16 -1 (-175 2650)(-175 2700);
WIRE 16 -1 (-175 2700)(-375 2700);
WIRE 16 -1 (-175 2600)(-175 2650);
WIRE 16 -1 (-175 2650)(-375 2650);
WIRE 16 -1 (-175 2600)(-375 2600);
WIRE 16 -1 (-175 2550)(-175 2600);
WIRE 16 -1 (-175 2500)(-175 2550);
WIRE 16 -1 (-175 2550)(-375 2550);
WIRE 16 -1 (-175 2450)(-175 2500);
WIRE 16 -1 (-175 2500)(-375 2500);
WIRE 16 -1 (-175 2400)(-175 2450);
WIRE 16 -1 (-175 2450)(-375 2450);
WIRE 16 -1 (-175 2350)(-175 2400);
WIRE 16 -1 (-175 2400)(-375 2400);
WIRE 16 -1 (-175 2300)(-175 2350);
WIRE 16 -1 (-175 2350)(-375 2350);
WIRE 16 -1 (-175 2250)(-175 2300);
WIRE 16 -1 (-175 2300)(-375 2300);
WIRE 16 -1 (-175 2200)(-175 2250);
WIRE 16 -1 (-175 2250)(-375 2250);
WIRE 16 -1 (-175 2150)(-175 2200);
WIRE 16 -1 (-175 2200)(-375 2200);
WIRE 16 -1 (-175 2100)(-175 2150);
WIRE 16 -1 (-175 2150)(-375 2150);
WIRE 16 -1 (-175 2050)(-175 2100);
WIRE 16 -1 (-175 2100)(-375 2100);
WIRE 16 -1 (-175 2050)(-375 2050);
WIRE 16 -1 (-175 2000)(-175 2050);
WIRE 16 -1 (-175 1950)(-175 2000);
WIRE 16 -1 (-175 2000)(-375 2000);
WIRE 16 -1 (-175 1900)(-175 1950);
WIRE 16 -1 (-175 1950)(-375 1950);
WIRE 16 -1 (-175 1850)(-175 1900);
WIRE 16 -1 (-175 1900)(-375 1900);
WIRE 16 -1 (-175 1800)(-175 1850);
WIRE 16 -1 (-175 1850)(-375 1850);
WIRE 16 -1 (-175 1750)(-175 1800);
WIRE 16 -1 (-175 1800)(-375 1800);
WIRE 16 -1 (-175 1700)(-175 1750);
WIRE 16 -1 (-175 1750)(-375 1750);
WIRE 16 -1 (-175 1650)(-175 1700);
WIRE 16 -1 (-175 1700)(-375 1700);
WIRE 16 -1 (-175 1600)(-175 1650);
WIRE 16 -1 (-175 1650)(-375 1650);
WIRE 16 -1 (-175 1550)(-175 1600);
WIRE 16 -1 (-175 1600)(-375 1600);
WIRE 16 -1 (-175 1550)(-375 1550);
WIRE 16 -1 (-175 1500)(-175 1550);
WIRE 16 -1 (-175 1450)(-175 1500);
WIRE 16 -1 (-175 1500)(-375 1500);
WIRE 16 -1 (-175 1400)(-175 1450);
WIRE 16 -1 (-175 1450)(-375 1450);
WIRE 16 -1 (-175 1350)(-175 1400);
WIRE 16 -1 (-175 1400)(-375 1400);
WIRE 16 -1 (-175 1300)(-175 1350);
WIRE 16 -1 (-175 1350)(-375 1350);
WIRE 16 -1 (-175 1250)(-175 1300);
WIRE 16 -1 (-175 1300)(-375 1300);
WIRE 16 -1 (-175 1200)(-175 1250);
WIRE 16 -1 (-175 1250)(-375 1250);
WIRE 16 -1 (-175 1150)(-175 1200);
WIRE 16 -1 (-175 1200)(-375 1200);
WIRE 16 -1 (-175 1100)(-175 1150);
WIRE 16 -1 (-175 1150)(-375 1150);
WIRE 16 -1 (-175 1050)(-175 1100);
WIRE 16 -1 (-175 1100)(-375 1100);
WIRE 16 -1 (-175 1050)(-375 1050);
WIRE 16 -1 (-175 1000)(-175 1050);
WIRE 16 -1 (-175 950)(-175 1000);
WIRE 16 -1 (-175 1000)(-375 1000);
WIRE 16 -1 (-175 900)(-175 950);
WIRE 16 -1 (-175 950)(-375 950);
WIRE 16 -1 (-175 850)(-175 900);
WIRE 16 -1 (-175 900)(-375 900);
WIRE 16 -1 (-175 800)(-175 850);
WIRE 16 -1 (-175 850)(-375 850);
WIRE 16 -1 (-175 750)(-175 800);
WIRE 16 -1 (-175 800)(-375 800);
WIRE 16 -1 (-175 700)(-175 750);
WIRE 16 -1 (-175 750)(-375 750);
WIRE 16 -1 (-175 600)(-175 700);
WIRE 16 -1 (-175 700)(-375 700);
WIRE 16 -1 (-2575 2250)(-2375 2250);
WIRE 16 -1 (-2375 2250)(-2375 2300);
WIRE 16 -1 (-2575 2300)(-2375 2300);
WIRE 16 -1 (-2375 2300)(-2375 2375);
WIRE 16 -1 (-7225 900)(-7225 800);
WIRE 16 -1 (-3775 600)(-3575 600);
WIRE 16 -1 (-3775 600)(-3775 650);
WIRE 16 -1 (-3775 650)(-3575 650);
WIRE 16 -1 (-3775 650)(-3775 700);
WIRE 16 -1 (-3775 700)(-3575 700);
WIRE 16 -1 (-3775 700)(-3775 750);
WIRE 16 -1 (-3775 750)(-3575 750);
WIRE 16 -1 (-3775 750)(-3775 800);
WIRE 16 -1 (-3775 800)(-3575 800);
WIRE 16 -1 (-3775 800)(-3775 850);
WIRE 16 -1 (-3775 850)(-3575 850);
WIRE 16 -1 (-3775 850)(-3775 900);
WIRE 16 -1 (-3775 900)(-3575 900);
WIRE 16 -1 (-3775 900)(-3775 950);
WIRE 16 -1 (-3775 950)(-3575 950);
WIRE 16 -1 (-3775 950)(-3775 1000);
WIRE 16 -1 (-3775 1000)(-3775 1050);
WIRE 16 -1 (-3775 1000)(-3575 1000);
WIRE 16 -1 (-3775 1050)(-3575 1050);
WIRE 16 -1 (-3775 1050)(-3775 1100);
WIRE 16 -1 (-3775 1100)(-3575 1100);
WIRE 16 -1 (-3775 1100)(-3775 1150);
WIRE 16 -1 (-3775 1150)(-3575 1150);
WIRE 16 -1 (-3775 1150)(-3775 1200);
WIRE 16 -1 (-3775 1200)(-3575 1200);
WIRE 16 -1 (-3775 1200)(-3775 1250);
WIRE 16 -1 (-3775 1250)(-3575 1250);
WIRE 16 -1 (-3775 1250)(-3775 1300);
WIRE 16 -1 (-3775 1300)(-3575 1300);
WIRE 16 -1 (-3775 1300)(-3775 1350);
WIRE 16 -1 (-3775 1350)(-3575 1350);
WIRE 16 -1 (-3775 1350)(-3775 1400);
WIRE 16 -1 (-3775 1400)(-3575 1400);
WIRE 16 -1 (-3775 1400)(-3775 1450);
WIRE 16 -1 (-3775 1450)(-3575 1450);
WIRE 16 -1 (-3775 1450)(-3775 1500);
WIRE 16 -1 (-3775 1500)(-3575 1500);
WIRE 16 -1 (-3775 1500)(-3775 1550);
WIRE 16 -1 (-3775 1550)(-3575 1550);
WIRE 16 -1 (-3775 1550)(-3775 1600);
WIRE 16 -1 (-3775 1600)(-3575 1600);
WIRE 16 -1 (-3775 1600)(-3775 1650);
WIRE 16 -1 (-3775 1650)(-3575 1650);
WIRE 16 -1 (-3775 1650)(-3775 1700);
WIRE 16 -1 (-3775 1700)(-3575 1700);
WIRE 16 -1 (-3775 1700)(-3775 1750);
WIRE 16 -1 (-3775 1750)(-3575 1750);
WIRE 16 -1 (-3775 1750)(-3775 1800);
WIRE 16 -1 (-3775 1800)(-3575 1800);
WIRE 16 -1 (-3775 1800)(-3775 1850);
WIRE 16 -1 (-3775 1850)(-3575 1850);
WIRE 16 -1 (-4175 1850)(-3775 1850);
WIRE 16 -1 (-4175 1925)(-4175 1850);
WIRE 16 -1 (-3775 1950)(-3575 1950);
WIRE 16 -1 (-3775 1950)(-3775 2000);
WIRE 16 -1 (-3775 2000)(-3575 2000);
WIRE 16 -1 (-3925 2000)(-3775 2000);
WIRE 16 -1 (-3925 2100)(-3925 2000);
WIRE 16 -1 (-5725 1400)(-5850 1400);
WIRE 16 -1 (-5850 1400)(-5850 1450);
WIRE 16 -1 (-5725 1450)(-5850 1450);
WIRE 16 -1 (-5850 1450)(-5850 1550);
WIRE 16 -1 (-5725 1550)(-5850 1550);
WIRE 16 -1 (-5850 1550)(-7825 1550);
WIRE 16 -1 (-7825 1650)(-7825 1550);
WIRE 16 -1 (-3775 2100)(-3575 2100);
WIRE 16 -1 (-3775 2100)(-3775 2150);
WIRE 16 -1 (-3775 2150)(-3575 2150);
WIRE 16 -1 (-3775 2150)(-3775 2200);
WIRE 16 -1 (-3775 2200)(-3575 2200);
WIRE 16 -1 (-3775 2200)(-3775 2250);
WIRE 16 -1 (-3775 2250)(-3575 2250);
WIRE 16 -1 (-3775 2250)(-3775 2300);
WIRE 16 -1 (-3775 2300)(-3575 2300);
WIRE 16 -1 (-3775 2400)(-3775 2300);
WIRE 16 -1 (-6175 1750)(-5725 1750);
WIRE 16 -1 (-6175 1750)(-6175 2050);
WIRE 16 -1 (-6175 2050)(-6900 2050);
FORCEPROP 2 LAST SIG_NAME FM_DIMM_EVENT_COD_N
J 0
(-6855 2060);
DISPLAY 0.617021 (-6855 2060);
PAINT ORANGE (-6855 2060);
WIRE 16 -1 (-5725 1200)(-7225 1200);
FORCEPROP 2 LAST SIG_NAME M_H_VREF
J 0
(-6525 1210);
DISPLAY 0.617021 (-6525 1210);
PAINT ORANGE (-6525 1210);
WIRE 16 -1 (-7275 1200)(-7225 1200);
WIRE 16 -1 (-7225 1200)(-7225 1100);
WIRE 16 -1 (-6575 1100)(-5725 1100);
FORCEPROP 2 LAST SIG_NAME TP_CH_H_DIMM0_RFU_2
J 0
(-6525 1110);
DISPLAY 0.617021 (-6525 1110);
PAINT ORANGE (-6525 1110);
FORCEPROP 2 LASTPROP $XRERR UNIQUE?
J 0
(-6815 1100);
DISPLAY 0.638298 (-6815 1100);
PAINT MONO (-6815 1100);
DISPLAY INVISIBLE (-6815 1100);
WIRE 16 -1 (-6575 1000)(-5725 1000);
FORCEPROP 2 LAST SIG_NAME TP_CH_H_DIMM0_RFU_0
J 0
(-6525 1010);
DISPLAY 0.617021 (-6525 1010);
PAINT ORANGE (-6525 1010);
FORCEPROP 2 LASTPROP $XRERR UNIQUE?
J 0
(-6815 1000);
DISPLAY 0.638298 (-6815 1000);
PAINT MONO (-6815 1000);
DISPLAY INVISIBLE (-6815 1000);
WIRE 16 -1 (-6575 1050)(-5725 1050);
FORCEPROP 2 LAST SIG_NAME TP_CH_H_DIMM0_RFU_1
J 0
(-6525 1060);
DISPLAY 0.617021 (-6525 1060);
PAINT ORANGE (-6525 1060);
FORCEPROP 2 LASTPROP $XRERR UNIQUE?
J 0
(-6815 1050);
DISPLAY 0.638298 (-6815 1050);
PAINT MONO (-6815 1050);
DISPLAY INVISIBLE (-6815 1050);
WIRE 16 -1 (-5725 1650)(-6575 1650);
FORCEPROP 2 LAST SIG_NAME M_H_ACT_N
J 0
(-6525 1660);
DISPLAY 0.617021 (-6525 1660);
PAINT ORANGE (-6525 1660);
WIRE 16 -1 (-6575 900)(-5725 900);
FORCEPROP 2 LAST SIG_NAME FM_ADR_COMPLETE_GHJ_N
J 0
(-6525 910);
DISPLAY 0.617021 (-6525 910);
PAINT ORANGE (-6525 910);
WIRE 16 -1 (-6575 1300)(-5725 1300);
FORCEPROP 2 LAST SIG_NAME SMB_DDR_GHJ_VPP_SCL
J 0
(-6535 1310);
DISPLAY 0.617021 (-6535 1310);
PAINT ORANGE (-6535 1310);
WIRE 16 -1 (-6575 1350)(-5725 1350);
WIRE 16 -1 (-5725 1700)(-6600 1700);
FORCEPROP 2 LAST SIG_NAME M_H_ALERT_N
J 0
(-6550 1710);
DISPLAY 0.617021 (-6550 1710);
PAINT ORANGE (-6550 1710);
WIRE 16 -1 (-5725 2000)(-5925 2000);
WIRE 16 -1 (-5725 1950)(-5925 1950);
WIRE 16 -1 (-4525 2000)(-4725 2000);
WIRE 16 -1 (-4525 1850)(-4725 1850);
WIRE 16 -1 (-4525 1750)(-4725 1750);
WIRE 16 -1 (-4525 1700)(-4725 1700);
WIRE 16 -1 (-4525 1600)(-4725 1600);
WIRE 16 -1 (-4525 1500)(-4725 1500);
WIRE 16 -1 (-4525 1250)(-4725 1250);
WIRE 16 -1 (-4525 1200)(-4725 1200);
WIRE 16 -1 (-4525 1950)(-4725 1950);
WIRE 16 -1 (-4525 1400)(-4725 1400);
WIRE 16 -1 (-4525 1300)(-4725 1300);
WIRE 16 -1 (-4525 1350)(-4725 1350);
WIRE 16 -1 (-4525 1550)(-4725 1550);
WIRE 16 -1 (-4525 1650)(-4725 1650);
WIRE 16 -1 (-4525 1900)(-4725 1900);
WIRE 16 -1 (-4525 1450)(-4725 1450);
WIRE 16 -1 (-4525 1800)(-4725 1800);
WIRE 16 -1 (-6075 1850)(-6075 2300);
WIRE 16 -1 (-5725 1850)(-6075 1850);
WIRE 16 -1 (-6075 2300)(-6575 2300);
FORCEPROP 2 LAST SIG_NAME M_H_PAR
J 0
(-6550 2310);
DISPLAY 0.617021 (-6550 2310);
PAINT ORANGE (-6550 2310);
WIRE 16 -1 (-6125 1800)(-6125 2250);
WIRE 16 -1 (-5725 1800)(-6125 1800);
WIRE 16 -1 (-6125 2250)(-6575 2250);
FORCEPROP 2 LAST SIG_NAME M_GHJ_RST_N
J 0
(-6550 2260);
DISPLAY 0.617021 (-6550 2260);
PAINT ORANGE (-6550 2260);
WIRE 16 -1 (-5725 2250)(-5925 2250);
WIRE 16 -1 (-5725 2200)(-5925 2200);
WIRE 16 -1 (-5725 2150)(-5925 2150);
WIRE 16 -1 (-5725 2100)(-5925 2100);
WIRE 16 -1 (-5725 2050)(-5925 2050);
WIRE 16 -1 (-5725 2300)(-5925 2300);
WIRE 16 -1 (-5725 2400)(-5925 2400);
WIRE 16 -1 (-5725 2450)(-5925 2450);
WIRE 16 -1 (-5725 2550)(-5925 2550);
WIRE 16 -1 (-5925 2900)(-5725 2900);
WIRE 16 -1 (-5925 2950)(-5925 2900);
WIRE 16 -1 (-5925 2950)(-6575 2950);
FORCEPROP 2 LAST SIG_NAME M_H_C<2>
J 0
(-6550 2960);
DISPLAY 0.617021 (-6550 2960);
PAINT ORANGE (-6550 2960);
WIRE 16 -1 (-5725 3050)(-5925 3050);
WIRE 16 -1 (-5725 2850)(-5925 2850);
WIRE 16 -1 (-5725 2800)(-5925 2800);
WIRE 16 -1 (-5725 2750)(-5925 2750);
WIRE 16 -1 (-5725 2600)(-5925 2600);
WIRE 16 -1 (-5725 2700)(-5925 2700);
WIRE 16 -1 (-5725 3000)(-6125 3000);
WIRE 16 -1 (-5725 3400)(-5925 3400);
WIRE 16 -1 (-5725 3500)(-5925 3500);
WIRE 16 -1 (-5725 3550)(-5925 3550);
WIRE 16 -1 (-5725 3250)(-5925 3250);
WIRE 16 -1 (-5725 3300)(-5925 3300);
WIRE 16 -1 (-5725 3350)(-5925 3350);
WIRE 16 -1 (-5725 3150)(-5925 3150);
WIRE 16 -1 (-5725 3100)(-6125 3100);
WIRE 16 -1 (-5725 3650)(-5925 3650);
WIRE 16 -1 (-5725 3700)(-5925 3700);
WIRE 16 -1 (-5725 3750)(-5925 3750);
WIRE 16 -1 (-5725 3800)(-5925 3800);
WIRE 16 -1 (-5725 3850)(-5925 3850);
WIRE 16 -1 (-5725 3900)(-5925 3900);
WIRE 16 -1 (-5725 3950)(-5925 3950);
WIRE 16 -1 (-5725 3600)(-5925 3600);
WIRE 16 -1 (-5725 4000)(-5925 4000);
WIRE 16 -1 (-5725 4050)(-5925 4050);
WIRE 16 -1 (-4525 2650)(-4725 2650);
WIRE 16 -1 (-4525 2600)(-4725 2600);
WIRE 16 -1 (-4525 3050)(-4725 3050);
WIRE 16 -1 (-4525 2900)(-4725 2900);
WIRE 16 -1 (-4525 2850)(-4725 2850);
WIRE 16 -1 (-4525 2800)(-4725 2800);
WIRE 16 -1 (-4525 2750)(-4725 2750);
WIRE 16 -1 (-4525 2700)(-4725 2700);
WIRE 16 -1 (-4525 2400)(-4725 2400);
WIRE 16 -1 (-4525 2300)(-4725 2300);
WIRE 16 -1 (-4525 2250)(-4725 2250);
WIRE 16 -1 (-4525 2200)(-4725 2200);
WIRE 16 -1 (-4525 2100)(-4725 2100);
WIRE 16 -1 (-4525 2950)(-4725 2950);
WIRE 16 -1 (-4525 3000)(-4725 3000);
WIRE 16 -1 (-4525 2550)(-4725 2550);
WIRE 16 -1 (-4525 2050)(-4725 2050);
WIRE 16 -1 (-4525 2350)(-4725 2350);
WIRE 16 -1 (-4525 2450)(-4725 2450);
WIRE 16 -1 (-4525 2500)(-4725 2500);
WIRE 16 -1 (-4525 2150)(-4725 2150);
WIRE 16 -1 (-4525 4000)(-4725 4000);
WIRE 16 -1 (-4525 3950)(-4725 3950);
WIRE 16 -1 (-4525 3500)(-4725 3500);
WIRE 16 -1 (-4525 3450)(-4725 3450);
WIRE 16 -1 (-4525 3400)(-4725 3400);
WIRE 16 -1 (-4525 3350)(-4725 3350);
WIRE 16 -1 (-4525 3300)(-4725 3300);
WIRE 16 -1 (-4525 3250)(-4725 3250);
WIRE 16 -1 (-4525 3200)(-4725 3200);
WIRE 16 -1 (-4525 3150)(-4725 3150);
WIRE 16 -1 (-4525 3100)(-4725 3100);
WIRE 16 -1 (-4525 4050)(-4725 4050);
WIRE 16 -1 (-4525 3900)(-4725 3900);
WIRE 16 -1 (-4525 3850)(-4725 3850);
WIRE 16 -1 (-4525 3800)(-4725 3800);
WIRE 16 -1 (-4525 3750)(-4725 3750);
WIRE 16 -1 (-4525 3650)(-4725 3650);
WIRE 16 -1 (-4525 3600)(-4725 3600);
WIRE 16 -1 (-4525 3550)(-4725 3550);
WIRE 16 -1 (-4525 3700)(-4725 3700);
WIRE 16 -1 (-5725 4100)(-5925 4100);
WIRE 16 -1 (-5725 4150)(-5925 4150);
WIRE 16 -1 (-5725 4350)(-5925 4350);
WIRE 16 -1 (-5725 4200)(-5925 4200);
WIRE 16 -1 (-5725 4250)(-5925 4250);
WIRE 16 -1 (-5725 4300)(-5925 4300);
WIRE 16 -1 (-4525 4250)(-4725 4250);
WIRE 16 -1 (-4525 4200)(-4725 4200);
WIRE 16 -1 (-4525 4150)(-4725 4150);
WIRE 16 -1 (-4525 4100)(-4725 4100);
WIRE 16 -1 (-4525 4300)(-4725 4300);
WIRE 16 -1 (-4525 4350)(-4725 4350);
WIRE 16 -1 (-1825 2850)(-2225 2850);
WIRE 16 -1 (-2025 2900)(-2225 2900);
WIRE 16 -1 (-1825 3850)(-2225 3850);
WIRE 16 -1 (-2025 3900)(-2225 3900);
WIRE 16 -1 (-1825 3950)(-2225 3950);
WIRE 16 -1 (-2025 4000)(-2225 4000);
WIRE 16 -1 (-1825 4050)(-2225 4050);
WIRE 16 -1 (-1825 2950)(-2225 2950);
WIRE 16 -1 (-2025 3000)(-2225 3000);
WIRE 16 -1 (-1825 3050)(-2225 3050);
WIRE 16 -1 (-2025 3100)(-2225 3100);
WIRE 16 -1 (-1825 3150)(-2225 3150);
WIRE 16 -1 (-2025 3200)(-2225 3200);
WIRE 16 -1 (-1825 3250)(-2225 3250);
WIRE 16 -1 (-2025 3300)(-2225 3300);
WIRE 16 -1 (-1825 3350)(-2225 3350);
WIRE 16 -1 (-2025 3400)(-2225 3400);
WIRE 16 -1 (-1825 3450)(-2225 3450);
WIRE 16 -1 (-2025 3500)(-2225 3500);
WIRE 16 -1 (-1825 3550)(-2225 3550);
WIRE 16 -1 (-2025 3600)(-2225 3600);
WIRE 16 -1 (-1825 3650)(-2225 3650);
WIRE 16 -1 (-2025 3700)(-2225 3700);
WIRE 16 -1 (-1825 3750)(-2225 3750);
WIRE 16 -1 (-2025 3800)(-2225 3800);
WIRE 16 -1 (-2025 4100)(-2225 4100);
WIRE 16 -1 (-1825 4150)(-2225 4150);
WIRE 16 -1 (-2025 4200)(-2225 4200);
WIRE 16 -1 (-1825 4250)(-2225 4250);
WIRE 16 -1 (-2025 4300)(-2225 4300);
WIRE 16 -1 (-1825 4350)(-2225 4350);
WIRE 16 -1 (-2025 4400)(-2225 4400);
WIRE 16 -1 (-1825 4450)(-2225 4450);
WIRE 16 -1 (-2025 4500)(-2225 4500);
WIRE 16 -1 (-1825 4550)(-2225 4550);
WIRE 16 -1 (-2025 4600)(-2225 4600);
DOT 1 (-3775 1800);
DOT 1 (-2375 2300);
DOT 1 (-1575 1950);
DOT 1 (-175 2950);
DOT 1 (-175 2900);
DOT 1 (-175 2850);
DOT 1 (-175 2800);
DOT 1 (-175 2750);
DOT 1 (-175 2700);
DOT 1 (-175 2600);
DOT 1 (-175 2650);
DOT 1 (-175 2550);
DOT 1 (-175 2500);
DOT 1 (-175 2450);
DOT 1 (-175 2400);
DOT 1 (-175 2350);
DOT 1 (-175 2300);
DOT 1 (-175 2250);
DOT 1 (-175 2200);
DOT 1 (-175 2150);
DOT 1 (-175 2100);
DOT 1 (-175 2050);
DOT 1 (-175 2000);
DOT 1 (-175 1950);
DOT 1 (-175 1900);
DOT 1 (-175 1850);
DOT 1 (-175 1800);
DOT 1 (-175 1750);
DOT 1 (-175 1700);
DOT 1 (-175 1650);
DOT 1 (-175 1600);
DOT 1 (-175 1550);
DOT 1 (-175 1500);
DOT 1 (-175 1450);
DOT 1 (-175 1400);
DOT 1 (-175 1350);
DOT 1 (-175 1300);
DOT 1 (-175 1250);
DOT 1 (-175 1200);
DOT 1 (-175 1150);
DOT 1 (-175 1100);
DOT 1 (-175 1050);
DOT 1 (-175 1000);
DOT 1 (-175 950);
DOT 1 (-175 900);
DOT 1 (-175 850);
DOT 1 (-175 800);
DOT 1 (-175 750);
DOT 1 (-175 700);
DOT 1 (-1575 2950);
DOT 1 (-1575 2900);
DOT 1 (-1575 2850);
DOT 1 (-1575 2800);
DOT 1 (-1575 2750);
DOT 1 (-1575 2700);
DOT 1 (-1575 2600);
DOT 1 (-1575 2650);
DOT 1 (-1575 2550);
DOT 1 (-1575 2500);
DOT 1 (-1575 2450);
DOT 1 (-1575 2400);
DOT 1 (-1575 2300);
DOT 1 (-1575 2350);
DOT 1 (-1575 2250);
DOT 1 (-1575 2200);
DOT 1 (-1575 2150);
DOT 1 (-1575 2050);
DOT 1 (-1575 2000);
DOT 1 (-1575 1900);
DOT 1 (-1575 1800);
DOT 1 (-1575 1850);
DOT 1 (-1575 1750);
DOT 1 (-1575 1700);
DOT 1 (-1575 1650);
DOT 1 (-1575 1600);
DOT 1 (-1575 1550);
DOT 1 (-1575 1500);
DOT 1 (-1575 1450);
DOT 1 (-1575 1400);
DOT 1 (-1575 1350);
DOT 1 (-1575 1300);
DOT 1 (-1575 1250);
DOT 1 (-1575 1200);
DOT 1 (-1575 1150);
DOT 1 (-1575 1100);
DOT 1 (-1575 1050);
DOT 1 (-1575 1000);
DOT 1 (-1575 950);
DOT 1 (-1575 900);
DOT 1 (-1575 850);
DOT 1 (-1575 800);
DOT 1 (-1575 750);
DOT 1 (-1575 700);
DOT 1 (-3775 2300);
DOT 1 (-3775 2150);
DOT 1 (-3775 2250);
DOT 1 (-3775 2200);
DOT 1 (-3775 1850);
DOT 1 (-3775 2000);
DOT 1 (-3775 1550);
DOT 1 (-3775 1750);
DOT 1 (-3775 1700);
DOT 1 (-3775 1650);
DOT 1 (-3775 1600);
DOT 1 (-3775 1500);
DOT 1 (-3775 1450);
DOT 1 (-3775 1400);
DOT 1 (-3775 1350);
DOT 1 (-3775 1300);
DOT 1 (-3775 1250);
DOT 1 (-3775 1000);
DOT 1 (-3775 1150);
DOT 1 (-3775 1200);
DOT 1 (-3775 1100);
DOT 1 (-3775 1050);
DOT 1 (-3775 750);
DOT 1 (-3775 900);
DOT 1 (-3775 850);
DOT 1 (-3775 800);
DOT 1 (-3775 650);
DOT 1 (-7225 1200);
DOT 1 (-3775 700);
DOT 1 (-3775 950);
DOT 1 (-5850 1550);
DOT 1 (-5850 1450);
DOT 1 (-1575 2100);
FORCENOTE
PLACE CAP NEAR DIMM CONNECTOR
(-7913 502) 0;
DISPLAY LEFT (-7913 502);
DISPLAY 1.574468 (-7913 502);
PAINT PURPLE (-7913 502);
FORCENOTE
SMBUS ADDR: 0XA6
(-7900 275) 0;
DISPLAY LEFT (-7900 275);
DISPLAY 1.957447 (-7900 275);
PAINT PURPLE (-7900 275);
QUIT
